FILE_TYPE = MACRO_DRAWING;
SET COLOR_WIRE YELLOW;
SET COLOR_PROP ORANGE;
SET COLOR_DOT WHITE;
SET COLOR_ARC YELLOW;
SET COLOR_BODY GREEN;
SET COLOR_NOTE PURPLE;
SET PROP_DISPLAY VALUE;
SET PAGE_NUMBER P273;
FORCEADD Q_RES..2
(-5125 5550);
FORCEPROP 1 LAST LOCATION R336
J 0
(-5080 5675);
DISPLAY 0.978723 (-5080 5675);
FORCEPROP 2 LAST $SEC 1
J 0
(-5075 5775);
DISPLAY 0.680851 (-5075 5775);
PAINT MONO (-5075 5775);
DISPLAY INVISIBLE (-5075 5775);
FORCEPROP 2 LAST CDS_SEC 1
J 0
(-5075 5775);
DISPLAY 1.021277 (-5075 5775);
DISPLAY INVISIBLE (-5075 5775);
FORCEPROP 1 LASTPIN (-5125 5650) $PN 1
J 0
(-5120 5612);
DISPLAY 0.787234 (-5120 5612);
FORCEPROP 1 LASTPIN (-5125 5450) $PN 2
J 0
(-5120 5460);
DISPLAY 0.787234 (-5120 5460);
FORCEPROP 1 LAST WATTAGE 1/16W
J 0
(-5085 5525);
DISPLAY 0.617021 (-5085 5525);
FORCEPROP 1 LAST VALUE 100K
J 0
(-5080 5625);
DISPLAY 0.617021 (-5080 5625);
FORCEPROP 1 LAST TOLERANCE 1%
J 0
(-5080 5575);
DISPLAY 0.617021 (-5080 5575);
FORCEPROP 1 LAST MATERIAL CHIP
J 0
(-5085 5475);
DISPLAY 0.617021 (-5085 5475);
FORCEPROP 1 LAST PACK_TYPE 0402LF
J 0
(-5085 5375);
DISPLAY 0.617021 (-5085 5375);
FORCEPROP 1 LAST PART_NUMBER CS41002FB09
J 0
(-5085 5425);
DISPLAY 0.617021 (-5085 5425);
DISPLAY INVISIBLE (-5085 5425);
FORCEPROP 2 LAST CDS_LIB pure_quanta
J 0
(-5125 5550);
PAINT MONO (-5125 5550);
DISPLAY INVISIBLE (-5125 5550);
FORCEPROP 2 LAST BOM_COST VR_SYSTEM 
J 0
(-5075 5725);
DISPLAY 0.680851 (-5075 5725);
DISPLAY INVISIBLE (-5075 5725);
FORCEPROP 2 LAST REUSE_ID 1
J 0
(-5075 5775);
DISPLAY 0.680851 (-5075 5775);
DISPLAY INVISIBLE (-5075 5775);
FORCEPROP 1 LAST PATH I10
J 0
(-5075 5725);
DISPLAY 0.978723 (-5075 5725);
PAINT WHITE (-5075 5725);
DISPLAY INVISIBLE (-5075 5725);
FORCEADD P1V0_AUX..1
(-1450 3275);
FORCEPROP 3 LASTPIN (-1450 3225) SIG_NAME P3V3_AUX\g
J 0
(-1440 3235);
DISPLAY 0.659574 (-1440 3235);
PAINT MONO (-1440 3235);
DISPLAY INVISIBLE (-1440 3235);
FORCEPROP 1 LAST HDL_POWER P3V3_AUX
J 1
(-1440 3315);
DISPLAY 0.617021 (-1440 3315);
PAINT GREEN (-1440 3315);
FORCEPROP 2 LAST BOM_COST VR_SYSTEM 
J 0
(-1424 3351);
DISPLAY 0.680851 (-1424 3351);
DISPLAY INVISIBLE (-1424 3351);
FORCEPROP 2 LAST CDS_LIB pure_quanta_power
J 0
(-1450 3275);
DISPLAY INVISIBLE (-1450 3275);
FORCEPROP 1 LAST PATH I100
J 0
(-1400 3300);
DISPLAY 0.872340 (-1400 3300);
PAINT AQUA (-1400 3300);
DISPLAY INVISIBLE (-1400 3300);
FORCEADD UNIVERSAL_GND..1
(-1450 2175);
FORCEPROP 3 LASTPIN (-1450 2225) SIG_NAME GND\g
J 0
(-1440 2235);
DISPLAY 0.659574 (-1440 2235);
PAINT MONO (-1440 2235);
DISPLAY INVISIBLE (-1440 2235);
FORCEPROP 0 LAST VOLTAGE 0
J 0
(-1450 2175);
PAINT SKYBLUE (-1450 2175);
DISPLAY INVISIBLE (-1450 2175);
FORCEPROP 2 LAST BOM_COST VR_SYSTEM 
J 0
(-1750 2250);
DISPLAY 0.680851 (-1750 2250);
DISPLAY INVISIBLE (-1750 2250);
FORCEPROP 2 LAST CDS_LIB pure_quanta_power
J 0
(-1450 2175);
DISPLAY INVISIBLE (-1450 2175);
FORCEPROP 1 LAST HDL_POWER GND
J 1
(-1425 2100);
DISPLAY 0.872340 (-1425 2100);
PAINT GREEN (-1425 2100);
DISPLAY INVISIBLE (-1425 2100);
FORCEPROP 1 LAST PATH I101
J 0
(-1375 2175);
DISPLAY 0.872340 (-1375 2175);
PAINT AQUA (-1375 2175);
DISPLAY INVISIBLE (-1375 2175);
FORCEADD Q_RES..1
(-625 2850);
FORCEPROP 1 LAST LOCATION R494
J 0
(-700 2950);
DISPLAY 0.787234 (-700 2950);
FORCEPROP 2 LAST SEC 1
J 0
(-675 3050);
DISPLAY 0.680851 (-675 3050);
PAINT MONO (-675 3050);
DISPLAY INVISIBLE (-675 3050);
FORCEPROP 1 LASTPIN (-725 2850) $PN 1
J 0
(-713 2862);
DISPLAY 0.787234 (-713 2862);
PAINT MONO (-713 2862);
FORCEPROP 1 LASTPIN (-525 2850) $PN 2
J 0
(-563 2862);
DISPLAY 0.787234 (-563 2862);
PAINT MONO (-563 2862);
FORCEPROP 1 LAST TOLERANCE 5%
J 0
(-550 2775);
DISPLAY 0.638298 (-550 2775);
FORCEPROP 1 LAST VALUE 0
J 2
(-600 2775);
DISPLAY 0.638298 (-600 2775);
FORCEPROP 1 LAST MATERIAL CHIP
J 0
(-825 2800);
DISPLAY 0.638298 (-825 2800);
FORCEPROP 1 LAST PACK_TYPE 0402LF
J 0
(-475 2800);
DISPLAY 0.638298 (-475 2800);
FORCEPROP 1 LAST PART_NUMBER CS00002JB13
J 0
(-775 2900);
DISPLAY 0.638298 (-775 2900);
DISPLAY INVISIBLE (-775 2900);
FORCEPROP 1 LAST WATTAGE 1/16W
J 2
(-650 2700);
DISPLAY 0.978723 (-650 2700);
DISPLAY INVISIBLE (-650 2700);
FORCEPROP 2 LAST CDS_LIB pure_quanta
J 0
(-625 2850);
DISPLAY INVISIBLE (-625 2850);
FORCEPROP 2 LAST SEC_TYPE 0402LF
J 0
(-675 3050);
DISPLAY 0.680851 (-675 3050);
DISPLAY INVISIBLE (-675 3050);
FORCEPROP 1 LAST PATH I102
J 0
(-675 3000);
DISPLAY 0.978723 (-675 3000);
PAINT WHITE (-675 3000);
DISPLAY INVISIBLE (-675 3000);
FORCEADD UNIVERSAL_GND..1
(300 2275);
FORCEPROP 3 LASTPIN (300 2325) SIG_NAME GND\g
J 0
(310 2335);
DISPLAY 0.659574 (310 2335);
PAINT MONO (310 2335);
DISPLAY INVISIBLE (310 2335);
FORCEPROP 0 LAST VOLTAGE 0
J 0
(300 2275);
PAINT SKYBLUE (300 2275);
DISPLAY INVISIBLE (300 2275);
FORCEPROP 2 LAST BOM_COST VR_SYSTEM 
J 0
(0 2350);
DISPLAY 0.680851 (0 2350);
DISPLAY INVISIBLE (0 2350);
FORCEPROP 2 LAST CDS_LIB pure_quanta_power
J 0
(300 2275);
DISPLAY INVISIBLE (300 2275);
FORCEPROP 1 LAST HDL_POWER GND
J 1
(325 2200);
DISPLAY 0.872340 (325 2200);
PAINT GREEN (325 2200);
DISPLAY INVISIBLE (325 2200);
FORCEPROP 1 LAST PATH I103
J 0
(375 2275);
DISPLAY 0.872340 (375 2275);
PAINT AQUA (375 2275);
DISPLAY INVISIBLE (375 2275);
FORCEADD Q_RES..2
R 2
(300 3325);
FORCEPROP 1 LAST LOCATION R552
J 2
(255 3450);
DISPLAY 0.978723 (255 3450);
FORCEPROP 0 LAST $SEC 1
J 0
(275 3500);
DISPLAY 0.680851 (275 3500);
PAINT MONO (275 3500);
DISPLAY INVISIBLE (275 3500);
FORCEPROP 0 LAST CDS_SEC 1
J 0
(275 3500);
DISPLAY 0.680851 (275 3500);
DISPLAY INVISIBLE (275 3500);
FORCEPROP 1 LASTPIN (300 3425) $PN 1
J 2
(295 3387);
DISPLAY 0.787234 (295 3387);
PAINT MONO (295 3387);
FORCEPROP 1 LASTPIN (300 3225) $PN 2
J 2
(295 3235);
DISPLAY 0.787234 (295 3235);
PAINT MONO (295 3235);
FORCEPROP 1 LAST VALUE 4.7K
J 2
(255 3400);
DISPLAY 0.978723 (255 3400);
FORCEPROP 1 LAST PACK_TYPE 0402LF
J 2
(260 3150);
DISPLAY 0.978723 (260 3150);
FORCEPROP 1 LAST TOLERANCE 5%
J 2
(255 3350);
DISPLAY 0.978723 (255 3350);
FORCEPROP 1 LAST WATTAGE 1/16W
J 2
(260 3300);
DISPLAY 0.978723 (260 3300);
FORCEPROP 1 LAST MATERIAL CHIP
J 2
(260 3250);
DISPLAY 0.978723 (260 3250);
FORCEPROP 1 LAST PART_NUMBER CS24702JB10
J 2
(260 3200);
DISPLAY 0.978723 (260 3200);
DISPLAY INVISIBLE (260 3200);
FORCEPROP 2 LAST CDS_LIB pure_quanta
J 0
(300 3325);
DISPLAY INVISIBLE (300 3325);
FORCEPROP 1 LAST PATH I104
J 2
(250 3500);
DISPLAY 0.978723 (250 3500);
PAINT WHITE (250 3500);
DISPLAY INVISIBLE (250 3500);
FORCEADD P1V0_AUX..1
(300 3575);
FORCEPROP 3 LASTPIN (300 3525) SIG_NAME P3V3_AUX\g
J 0
(310 3535);
DISPLAY 0.659574 (310 3535);
PAINT MONO (310 3535);
DISPLAY INVISIBLE (310 3535);
FORCEPROP 1 LAST HDL_POWER P3V3_AUX
J 1
(310 3615);
DISPLAY 0.617021 (310 3615);
PAINT GREEN (310 3615);
FORCEPROP 2 LAST BOM_COST VR_SYSTEM 
J 0
(326 3651);
DISPLAY 0.680851 (326 3651);
DISPLAY INVISIBLE (326 3651);
FORCEPROP 2 LAST CDS_LIB pure_quanta_power
J 0
(300 3575);
DISPLAY INVISIBLE (300 3575);
FORCEPROP 1 LAST PATH I105
J 0
(350 3600);
DISPLAY 0.872340 (350 3600);
PAINT AQUA (350 3600);
DISPLAY INVISIBLE (350 3600);
FORCEADD OFFPAGE..2
(1125 3175);
FORCEPROP 2 LAST $XR0 80 
J 0
(1314 3175);
DISPLAY 0.638298 (1314 3175);
PAINT MONO (1314 3175);
FORCEPROP 2 LAST CDS_LIB standard
J 0
(1125 3175);
DISPLAY INVISIBLE (1125 3175);
FORCEPROP 1 LAST OFFPAGE TRUE
J 0
(1450 3050);
DISPLAY 0.872340 (1450 3050);
PAINT GREEN (1450 3050);
DISPLAY INVISIBLE (1450 3050);
FORCEPROP 1 LAST COMMENT_BODY TRUE
J 0
(1080 3080);
DISPLAY 0.872340 (1080 3080);
PAINT GREEN (1080 3080);
DISPLAY INVISIBLE (1080 3080);
FORCEPROP 2 LAST PATH I106
J 0
(1300 3250);
DISPLAY 0.680851 (1300 3250);
DISPLAY INVISIBLE (1300 3250);
FORCEADD MOSFET_NCH_DUAL..1
(-1125 4025);
FORCEPROP 1 LAST LOCATION Q3
J 0
(-974 3999);
DISPLAY 0.723404 (-974 3999);
PAINT GREEN (-974 3999);
FORCEPROP 2 LAST SEC 1
J 0
(-950 4150);
DISPLAY 0.680851 (-950 4150);
PAINT MONO (-950 4150);
DISPLAY INVISIBLE (-950 4150);
FORCEPROP 2 LASTPIN (-1075 4225) $PN 6
R 1
J 0
(-1085 4235);
DISPLAY 0.680851 (-1085 4235);
PAINT MONO (-1085 4235);
FORCEPROP 2 LASTPIN (-1325 3975) $PN 2
J 2
(-1335 3985);
DISPLAY 0.680851 (-1335 3985);
PAINT MONO (-1335 3985);
FORCEPROP 2 LASTPIN (-1075 3825) $PN 1
R 1
J 2
(-1085 3815);
DISPLAY 0.680851 (-1085 3815);
PAINT MONO (-1085 3815);
FORCEPROP 1 LAST MATERIAL IC
J 0
(-974 3874);
DISPLAY 0.723404 (-974 3874);
PAINT GREEN (-974 3874);
FORCEPROP 2 LAST VALUE PJT138K
J 0
(-950 4050);
DISPLAY 0.680851 (-950 4050);
FORCEPROP 2 LAST PART_TYPE SMLF
J 0
(-950 4100);
DISPLAY 0.680851 (-950 4100);
FORCEPROP 1 LAST PART_NUMBER BAM138K0003
J 0
(-974 3939);
DISPLAY 0.723404 (-974 3939);
PAINT GREEN (-974 3939);
DISPLAY INVISIBLE (-974 3939);
FORCEPROP 2 LAST CDS_LIB pure_quanta
J 0
(-1125 4025);
DISPLAY INVISIBLE (-1125 4025);
FORCEPROP 1 LAST NEEDS_NO_SIZE TRUE
J 0
(-1125 4024);
DISPLAY 0.468085 (-1125 4024);
PAINT GREEN (-1125 4024);
DISPLAY INVISIBLE (-1125 4024);
FORCEPROP 1 LAST CDS_LMAN_SYM_OUTLINE -150,150,150,-150
J 0
(-1125 4025);
DISPLAY 0.468085 (-1125 4025);
PAINT GREEN (-1125 4025);
DISPLAY INVISIBLE (-1125 4025);
FORCEPROP 2 LAST SEC_TYPE 
J 0
(-950 4150);
DISPLAY 0.680851 (-950 4150);
DISPLAY INVISIBLE (-950 4150);
FORCEPROP 1 LAST PATH I107
J 0
(-1125 4025);
DISPLAY 0.723404 (-1125 4025);
PAINT GREEN (-1125 4025);
DISPLAY INVISIBLE (-1125 4025);
FORCEADD MOSFET_NCH_DUAL..2
(-325 4075);
FORCEPROP 1 LAST LOCATION Q3
J 0
(-174 4051);
DISPLAY 0.723404 (-174 4051);
PAINT GREEN (-174 4051);
FORCEPROP 2 LAST SEC 2
J 0
(-150 4200);
DISPLAY 0.680851 (-150 4200);
PAINT MONO (-150 4200);
DISPLAY INVISIBLE (-150 4200);
FORCEPROP 2 LASTPIN (-275 4275) $PN 3
R 1
J 0
(-285 4285);
DISPLAY 0.680851 (-285 4285);
PAINT MONO (-285 4285);
FORCEPROP 2 LASTPIN (-525 4025) $PN 5
J 2
(-535 4035);
DISPLAY 0.680851 (-535 4035);
PAINT MONO (-535 4035);
FORCEPROP 2 LASTPIN (-275 3875) $PN 4
R 1
J 2
(-285 3865);
DISPLAY 0.680851 (-285 3865);
PAINT MONO (-285 3865);
FORCEPROP 2 LAST PART_TYPE SMLF
J 0
(-150 4150);
DISPLAY 0.680851 (-150 4150);
FORCEPROP 1 LAST MATERIAL IC
J 0
(-174 3926);
DISPLAY 0.723404 (-174 3926);
PAINT GREEN (-174 3926);
FORCEPROP 2 LAST VALUE PJT138K
J 0
(-150 4100);
DISPLAY 0.680851 (-150 4100);
FORCEPROP 1 LAST PART_NUMBER BAM138K0003
J 0
(-174 3981);
DISPLAY 0.723404 (-174 3981);
PAINT GREEN (-174 3981);
DISPLAY INVISIBLE (-174 3981);
FORCEPROP 1 LAST CDS_LMAN_SYM_OUTLINE -150,150,150,-150
J 0
(-325 4075);
DISPLAY 0.468085 (-325 4075);
PAINT GREEN (-325 4075);
DISPLAY INVISIBLE (-325 4075);
FORCEPROP 1 LAST NEEDS_NO_SIZE TRUE
J 0
(-175 3966);
DISPLAY 0.468085 (-175 3966);
PAINT GREEN (-175 3966);
DISPLAY INVISIBLE (-175 3966);
FORCEPROP 2 LAST CDS_LIB pure_quanta
J 0
(-325 4075);
DISPLAY INVISIBLE (-325 4075);
FORCEPROP 2 LAST SEC_TYPE 
J 0
(-150 4200);
DISPLAY 0.680851 (-150 4200);
DISPLAY INVISIBLE (-150 4200);
FORCEPROP 1 LAST PATH I108
J 0
(-175 3925);
DISPLAY 0.723404 (-175 3925);
PAINT GREEN (-175 3925);
DISPLAY INVISIBLE (-175 3925);
FORCEADD UNIVERSAL_GND..1
(-1075 3550);
FORCEPROP 3 LASTPIN (-1075 3600) SIG_NAME GND\g
J 0
(-1065 3610);
DISPLAY 0.659574 (-1065 3610);
PAINT MONO (-1065 3610);
DISPLAY INVISIBLE (-1065 3610);
FORCEPROP 2 LAST CDS_LIB pure_quanta_power
J 0
(-1075 3550);
DISPLAY INVISIBLE (-1075 3550);
FORCEPROP 2 LAST BOM_COST VR_SYSTEM 
J 0
(-1375 3625);
DISPLAY 0.680851 (-1375 3625);
DISPLAY INVISIBLE (-1375 3625);
FORCEPROP 0 LAST VOLTAGE 0
J 0
(-1075 3550);
PAINT SKYBLUE (-1075 3550);
DISPLAY INVISIBLE (-1075 3550);
FORCEPROP 1 LAST HDL_POWER GND
J 1
(-1050 3475);
DISPLAY 0.872340 (-1050 3475);
PAINT GREEN (-1050 3475);
DISPLAY INVISIBLE (-1050 3475);
FORCEPROP 1 LAST PATH I109
J 0
(-1000 3550);
DISPLAY 0.872340 (-1000 3550);
PAINT AQUA (-1000 3550);
DISPLAY INVISIBLE (-1000 3550);
FORCEADD UNIVERSAL_POWER..1
(-5125 5825);
FORCEPROP 3 LASTPIN (-5125 5775) SIG_NAME P12V_AUX\g
J 0
(-5115 5785);
DISPLAY 0.659574 (-5115 5785);
PAINT MONO (-5115 5785);
DISPLAY INVISIBLE (-5115 5785);
FORCEPROP 1 LAST HDL_POWER P12V_AUX
J 1
(-5125 5875);
DISPLAY 0.617021 (-5125 5875);
PAINT GREEN (-5125 5875);
FORCEPROP 2 LAST BOM_COST VR_SYSTEM 
J 0
(-5125 5925);
DISPLAY 0.680851 (-5125 5925);
DISPLAY INVISIBLE (-5125 5925);
FORCEPROP 2 LAST CDS_LIB pure_quanta_power
J 0
(-5125 5825);
PAINT RED (-5125 5825);
DISPLAY INVISIBLE (-5125 5825);
FORCEPROP 1 LAST PATH I11
J 0
(-5075 5850);
DISPLAY 0.872340 (-5075 5850);
PAINT AQUA (-5075 5850);
DISPLAY INVISIBLE (-5075 5850);
FORCEADD UNIVERSAL_GND..1
(-275 3600);
FORCEPROP 3 LASTPIN (-275 3650) SIG_NAME GND\g
J 0
(-265 3660);
DISPLAY 0.659574 (-265 3660);
PAINT MONO (-265 3660);
DISPLAY INVISIBLE (-265 3660);
FORCEPROP 2 LAST CDS_LIB pure_quanta_power
J 0
(-275 3600);
DISPLAY INVISIBLE (-275 3600);
FORCEPROP 0 LAST VOLTAGE 0
J 0
(-275 3600);
PAINT SKYBLUE (-275 3600);
DISPLAY INVISIBLE (-275 3600);
FORCEPROP 2 LAST BOM_COST VR_SYSTEM 
J 0
(-575 3675);
DISPLAY 0.680851 (-575 3675);
DISPLAY INVISIBLE (-575 3675);
FORCEPROP 1 LAST HDL_POWER GND
J 1
(-250 3525);
DISPLAY 0.872340 (-250 3525);
PAINT GREEN (-250 3525);
DISPLAY INVISIBLE (-250 3525);
FORCEPROP 1 LAST PATH I110
J 0
(-200 3600);
DISPLAY 0.872340 (-200 3600);
PAINT AQUA (-200 3600);
DISPLAY INVISIBLE (-200 3600);
FORCEADD Q_RES..2
(-1075 4575);
FORCEPROP 1 LAST LOCATION R554
J 0
(-1030 4700);
DISPLAY 0.787234 (-1030 4700);
FORCEPROP 2 LAST SEC 1
J 0
(-1025 4800);
DISPLAY 0.680851 (-1025 4800);
PAINT MONO (-1025 4800);
DISPLAY INVISIBLE (-1025 4800);
FORCEPROP 1 LASTPIN (-1075 4675) $PN 1
J 0
(-1070 4637);
DISPLAY 0.787234 (-1070 4637);
PAINT MONO (-1070 4637);
FORCEPROP 1 LASTPIN (-1075 4475) $PN 2
J 0
(-1070 4485);
DISPLAY 0.787234 (-1070 4485);
PAINT MONO (-1070 4485);
FORCEPROP 1 LAST MATERIAL CHIP
J 0
(-1035 4500);
DISPLAY 0.787234 (-1035 4500);
FORCEPROP 1 LAST PACK_TYPE 0402LF
J 0
(-1035 4400);
DISPLAY 0.787234 (-1035 4400);
FORCEPROP 1 LAST WATTAGE 1/16W
J 0
(-1035 4550);
DISPLAY 0.787234 (-1035 4550);
FORCEPROP 1 LAST TOLERANCE 1%
J 0
(-1030 4600);
DISPLAY 0.787234 (-1030 4600);
FORCEPROP 1 LAST VALUE 100K
J 0
(-1030 4650);
DISPLAY 0.787234 (-1030 4650);
FORCEPROP 1 LAST PART_NUMBER CS41002FB09
J 0
(-1035 4450);
DISPLAY 0.787234 (-1035 4450);
DISPLAY INVISIBLE (-1035 4450);
FORCEPROP 2 LAST SEC_TYPE 0402LF
J 0
(-1025 4800);
DISPLAY 0.680851 (-1025 4800);
DISPLAY INVISIBLE (-1025 4800);
FORCEPROP 2 LAST CDS_LIB pure_quanta
J 0
(-1075 4575);
DISPLAY INVISIBLE (-1075 4575);
FORCEPROP 1 LAST PATH I111
J 0
(-1025 4750);
DISPLAY 0.978723 (-1025 4750);
PAINT WHITE (-1025 4750);
DISPLAY INVISIBLE (-1025 4750);
FORCEADD UNIVERSAL_POWER..1
(-1075 4950);
FORCEPROP 3 LASTPIN (-1075 4900) SIG_NAME P12V_AUX\g
J 0
(-1065 4910);
DISPLAY 0.659574 (-1065 4910);
PAINT MONO (-1065 4910);
DISPLAY INVISIBLE (-1065 4910);
FORCEPROP 1 LAST HDL_POWER P12V_AUX
J 1
(-1075 5000);
DISPLAY 0.617021 (-1075 5000);
PAINT GREEN (-1075 5000);
FORCEPROP 2 LAST BOM_COST VR_SYSTEM 
J 0
(-1075 5050);
DISPLAY 0.680851 (-1075 5050);
DISPLAY INVISIBLE (-1075 5050);
FORCEPROP 2 LAST CDS_LIB pure_quanta_power
J 0
(-1075 4950);
DISPLAY INVISIBLE (-1075 4950);
FORCEPROP 1 LAST PATH I112
J 0
(-1025 4975);
DISPLAY 0.872340 (-1025 4975);
PAINT AQUA (-1025 4975);
DISPLAY INVISIBLE (-1025 4975);
FORCEADD Q_RES..2
(-275 4575);
FORCEPROP 1 LAST LOCATION R569
J 0
(-230 4700);
DISPLAY 0.638298 (-230 4700);
FORCEPROP 0 LAST $SEC 1
J 0
(-225 4750);
DISPLAY 0.680851 (-225 4750);
PAINT MONO (-225 4750);
DISPLAY INVISIBLE (-225 4750);
FORCEPROP 0 LAST CDS_SEC 1
J 0
(-225 4750);
DISPLAY 0.680851 (-225 4750);
DISPLAY INVISIBLE (-225 4750);
FORCEPROP 1 LASTPIN (-275 4675) $PN 1
J 0
(-270 4637);
DISPLAY 0.787234 (-270 4637);
PAINT MONO (-270 4637);
FORCEPROP 1 LASTPIN (-275 4475) $PN 2
J 0
(-270 4485);
DISPLAY 0.787234 (-270 4485);
PAINT MONO (-270 4485);
FORCEPROP 1 LAST VALUE 1K
J 0
(-230 4650);
DISPLAY 0.638298 (-230 4650);
FORCEPROP 1 LAST PACK_TYPE 0402LF
J 0
(-235 4400);
DISPLAY 0.638298 (-235 4400);
FORCEPROP 1 LAST MATERIAL CHIP
J 0
(-235 4500);
DISPLAY 0.638298 (-235 4500);
FORCEPROP 1 LAST TOLERANCE 1%
J 0
(-230 4600);
DISPLAY 0.638298 (-230 4600);
FORCEPROP 1 LAST WATTAGE 1/16W
J 0
(-235 4550);
DISPLAY 0.638298 (-235 4550);
FORCEPROP 1 LAST PART_NUMBER CS21002FB06
J 0
(-235 4450);
DISPLAY 0.638298 (-235 4450);
DISPLAY INVISIBLE (-235 4450);
FORCEPROP 2 LAST CDS_LIB pure_quanta
J 0
(-275 4575);
DISPLAY INVISIBLE (-275 4575);
FORCEPROP 1 LAST PATH I113
J 0
(-225 4750);
DISPLAY 0.978723 (-225 4750);
PAINT WHITE (-225 4750);
DISPLAY INVISIBLE (-225 4750);
FORCEADD Q_RES..2
R 2
(-550 4925);
FORCEPROP 1 LAST LOCATION R568
J 2
(-595 5050);
DISPLAY 0.808511 (-595 5050);
FORCEPROP 0 LAST $SEC 1
J 0
(-575 5100);
DISPLAY 0.680851 (-575 5100);
PAINT MONO (-575 5100);
DISPLAY INVISIBLE (-575 5100);
FORCEPROP 0 LAST CDS_SEC 1
J 0
(-575 5100);
DISPLAY 0.680851 (-575 5100);
DISPLAY INVISIBLE (-575 5100);
FORCEPROP 1 LASTPIN (-550 5025) $PN 1
J 2
(-555 4987);
DISPLAY 0.787234 (-555 4987);
PAINT MONO (-555 4987);
FORCEPROP 1 LASTPIN (-550 4825) $PN 2
J 2
(-555 4835);
DISPLAY 0.787234 (-555 4835);
PAINT MONO (-555 4835);
FORCEPROP 1 LAST VALUE 10K
J 2
(-595 5000);
DISPLAY 0.510638 (-595 5000);
FORCEPROP 1 LAST PACK_TYPE 0402LF
J 2
(-590 4750);
DISPLAY 0.510638 (-590 4750);
FORCEPROP 1 LAST MATERIAL CHIP
J 2
(-590 4850);
DISPLAY 0.510638 (-590 4850);
FORCEPROP 1 LAST WATTAGE 1/16W
J 2
(-590 4900);
DISPLAY 0.510638 (-590 4900);
FORCEPROP 1 LAST TOLERANCE 1%
J 2
(-595 4950);
DISPLAY 0.510638 (-595 4950);
FORCEPROP 1 LAST PART_NUMBER CS31002FB08
J 2
(-590 4800);
DISPLAY 0.510638 (-590 4800);
DISPLAY INVISIBLE (-590 4800);
FORCEPROP 2 LAST CDS_LIB pure_quanta
J 2
(-550 4925);
DISPLAY INVISIBLE (-550 4925);
FORCEPROP 1 LAST PATH I114
J 2
(-600 5100);
DISPLAY 0.978723 (-600 5100);
PAINT WHITE (-600 5100);
DISPLAY INVISIBLE (-600 5100);
FORCEADD UNIVERSAL_POWER..1
(-550 5300);
FORCEPROP 3 LASTPIN (-550 5250) SIG_NAME P12V_AUX\g
J 0
(-540 5260);
DISPLAY 0.659574 (-540 5260);
PAINT MONO (-540 5260);
DISPLAY INVISIBLE (-540 5260);
FORCEPROP 1 LAST HDL_POWER P12V_AUX
J 1
(-550 5350);
DISPLAY 0.617021 (-550 5350);
PAINT GREEN (-550 5350);
FORCEPROP 2 LAST CDS_LIB pure_quanta_power
J 0
(-550 5300);
DISPLAY INVISIBLE (-550 5300);
FORCEPROP 2 LAST BOM_COST VR_SYSTEM 
J 0
(-550 5400);
DISPLAY 0.680851 (-550 5400);
DISPLAY INVISIBLE (-550 5400);
FORCEPROP 1 LAST PATH I115
J 0
(-500 5325);
DISPLAY 0.872340 (-500 5325);
PAINT AQUA (-500 5325);
DISPLAY INVISIBLE (-500 5325);
FORCEADD Q_CAP..1
(325 4575);
FORCEPROP 1 LAST LOCATION C29
J 0
(375 4675);
DISPLAY 0.978723 (375 4675);
FORCEPROP 0 LAST $SEC 1
J 0
(375 4725);
DISPLAY 0.680851 (375 4725);
PAINT MONO (375 4725);
DISPLAY INVISIBLE (375 4725);
FORCEPROP 0 LAST CDS_SEC 1
J 0
(375 4725);
DISPLAY 0.680851 (375 4725);
DISPLAY INVISIBLE (375 4725);
FORCEPROP 1 LASTPIN (325 4675) $PN 1
J 0
(335 4655);
DISPLAY 0.787234 (335 4655);
PAINT MONO (335 4655);
FORCEPROP 1 LASTPIN (325 4475) $PN 2
J 0
(335 4455);
DISPLAY 0.787234 (335 4455);
PAINT MONO (335 4455);
FORCEPROP 1 LAST PACK_TYPE C0402
J 0
(375 4375);
DISPLAY 0.978723 (375 4375);
FORCEPROP 1 LAST VALUE 0.22UF
J 0
(375 4625);
DISPLAY 0.978723 (375 4625);
FORCEPROP 1 LAST TOLERANCE 10%
J 0
(375 4525);
DISPLAY 0.978723 (375 4525);
FORCEPROP 1 LAST MATERIAL X7R
J 0
(375 4475);
DISPLAY 0.978723 (375 4475);
FORCEPROP 1 LAST VOLTAGE 25V
J 0
(375 4575);
DISPLAY 0.978723 (375 4575);
FORCEPROP 1 LAST PART_NUMBER CH4224K1B01
J 0
(375 4425);
DISPLAY 0.978723 (375 4425);
DISPLAY INVISIBLE (375 4425);
FORCEPROP 2 LAST CDS_LIB pure_quanta
J 0
(325 4575);
DISPLAY INVISIBLE (325 4575);
FORCEPROP 1 LAST PATH I116
J 0
(375 4725);
DISPLAY 0.978723 (375 4725);
PAINT WHITE (375 4725);
DISPLAY INVISIBLE (375 4725);
FORCEADD UNIVERSAL_GND..1
(325 4200);
FORCEPROP 3 LASTPIN (325 4250) SIG_NAME GND\g
J 0
(335 4260);
DISPLAY 0.659574 (335 4260);
PAINT MONO (335 4260);
DISPLAY INVISIBLE (335 4260);
FORCEPROP 0 LAST VOLTAGE 0
J 0
(325 4200);
PAINT SKYBLUE (325 4200);
DISPLAY INVISIBLE (325 4200);
FORCEPROP 2 LAST BOM_COST VR_SYSTEM 
J 0
(25 4275);
DISPLAY 0.680851 (25 4275);
DISPLAY INVISIBLE (25 4275);
FORCEPROP 2 LAST CDS_LIB pure_quanta_power
J 0
(325 4200);
DISPLAY INVISIBLE (325 4200);
FORCEPROP 1 LAST HDL_POWER GND
J 1
(350 4125);
DISPLAY 0.872340 (350 4125);
PAINT GREEN (350 4125);
DISPLAY INVISIBLE (350 4125);
FORCEPROP 1 LAST PATH I117
J 0
(400 4200);
DISPLAY 0.872340 (400 4200);
PAINT AQUA (400 4200);
DISPLAY INVISIBLE (400 4200);
FORCEADD OFFPAGE..2
(-4800 5150);
FORCEPROP 2 LAST $XR0 188 
J 0
(-4611 5150);
DISPLAY 0.638298 (-4611 5150);
PAINT MONO (-4611 5150);
FORCEPROP 2 LAST CDS_LIB standard
J 0
(-4800 5150);
DISPLAY INVISIBLE (-4800 5150);
FORCEPROP 2 LAST BOM_COST VR_SYSTEM 
J 0
(-5050 5200);
DISPLAY 0.829787 (-5050 5200);
PAINT PURPLE (-5050 5200);
DISPLAY INVISIBLE (-5050 5200);
FORCEPROP 1 LAST OFFPAGE TRUE
J 0
(-4475 5025);
DISPLAY 0.872340 (-4475 5025);
PAINT GREEN (-4475 5025);
DISPLAY INVISIBLE (-4475 5025);
FORCEPROP 1 LAST COMMENT_BODY TRUE
J 0
(-4845 5055);
DISPLAY 0.872340 (-4845 5055);
PAINT GREEN (-4845 5055);
DISPLAY INVISIBLE (-4845 5055);
FORCEPROP 2 LAST PATH I12
J 0
(-4600 5200);
DISPLAY 0.680851 (-4600 5200);
DISPLAY INVISIBLE (-4600 5200);
FORCEADD Q_RES..2
(-5500 2725);
FORCEPROP 1 LAST LOCATION R1492
J 0
(-5455 2850);
DISPLAY 0.617021 (-5455 2850);
PAINT SKYBLUE (-5455 2850);
FORCEPROP 0 LAST $SEC 1
J 0
(-5450 2900);
DISPLAY 0.680851 (-5450 2900);
PAINT MONO (-5450 2900);
DISPLAY INVISIBLE (-5450 2900);
FORCEPROP 0 LAST CDS_SEC 1
J 0
(-5450 2900);
DISPLAY 0.680851 (-5450 2900);
DISPLAY INVISIBLE (-5450 2900);
FORCEPROP 1 LASTPIN (-5500 2825) $PN 1
J 0
(-5495 2787);
DISPLAY 0.489362 (-5495 2787);
PAINT MONO (-5495 2787);
FORCEPROP 1 LASTPIN (-5500 2625) $PN 2
J 0
(-5495 2635);
DISPLAY 0.489362 (-5495 2635);
PAINT MONO (-5495 2635);
FORCEPROP 1 LAST PACK_TYPE 0402LF
J 0
(-5460 2550);
DISPLAY 0.489362 (-5460 2550);
PAINT SKYBLUE (-5460 2550);
FORCEPROP 1 LAST WATTAGE 1/16W
J 0
(-5460 2700);
DISPLAY 0.489362 (-5460 2700);
PAINT SKYBLUE (-5460 2700);
FORCEPROP 1 LAST VALUE 10K
J 0
(-5455 2800);
DISPLAY 0.489362 (-5455 2800);
PAINT SKYBLUE (-5455 2800);
FORCEPROP 1 LAST TOLERANCE 5%
J 0
(-5455 2750);
DISPLAY 0.489362 (-5455 2750);
PAINT SKYBLUE (-5455 2750);
FORCEPROP 1 LAST MATERIAL CHIP
J 0
(-5460 2650);
DISPLAY 0.489362 (-5460 2650);
PAINT SKYBLUE (-5460 2650);
FORCEPROP 1 LAST PART_NUMBER CS31002JB08
J 0
(-5460 2600);
DISPLAY 0.489362 (-5460 2600);
PAINT SKYBLUE (-5460 2600);
DISPLAY INVISIBLE (-5460 2600);
FORCEPROP 2 LAST CDS_LIB pure_quanta
J 0
(-5500 2725);
DISPLAY INVISIBLE (-5500 2725);
FORCEPROP 2 LAST BOM_COST VR_SYSTEM
J 0
(-5450 2900);
DISPLAY 0.680851 (-5450 2900);
DISPLAY INVISIBLE (-5450 2900);
FORCEPROP 1 LAST PATH I120
J 0
(-5450 2900);
DISPLAY 0.978723 (-5450 2900);
PAINT WHITE (-5450 2900);
DISPLAY INVISIBLE (-5450 2900);
FORCEADD UNIVERSAL_POWER..1
(-5500 3175);
FORCEPROP 3 LASTPIN (-5500 3125) SIG_NAME P3V3_AUX\g
J 0
(-5490 3135);
DISPLAY 0.659574 (-5490 3135);
PAINT MONO (-5490 3135);
DISPLAY INVISIBLE (-5490 3135);
FORCEPROP 1 LAST HDL_POWER P3V3_AUX
J 1
(-5500 3225);
DISPLAY 0.489362 (-5500 3225);
PAINT GREEN (-5500 3225);
FORCEPROP 2 LAST CDS_LIB pure_quanta_power
J 0
(-5500 3175);
DISPLAY INVISIBLE (-5500 3175);
FORCEPROP 2 LAST BOM_COST VR_SYSTEM
J 0
(-5500 3275);
DISPLAY 0.617021 (-5500 3275);
PAINT PURPLE (-5500 3275);
DISPLAY INVISIBLE (-5500 3275);
FORCEPROP 1 LAST PATH I121
J 0
(-5450 3200);
DISPLAY 0.872340 (-5450 3200);
PAINT AQUA (-5450 3200);
DISPLAY INVISIBLE (-5450 3200);
FORCEADD UNIVERSAL_GND..1
R 7
(-5425 2275);
FORCEPROP 3 LASTPIN (-5375 2275) SIG_NAME GND\g
J 0
(-5365 2285);
DISPLAY 0.659574 (-5365 2285);
PAINT MONO (-5365 2285);
DISPLAY INVISIBLE (-5365 2285);
FORCEPROP 2 LAST BOM_COST VR_SYSTEM
R 1
J 0
(-5350 1950);
DISPLAY 0.617021 (-5350 1950);
PAINT PURPLE (-5350 1950);
DISPLAY INVISIBLE (-5350 1950);
FORCEPROP 2 LAST CDS_LIB pure_quanta_power
J 0
(-5425 2275);
DISPLAY INVISIBLE (-5425 2275);
FORCEPROP 1 LAST HDL_POWER GND
R 1
J 1
(-5500 2300);
DISPLAY 0.872340 (-5500 2300);
PAINT GREEN (-5500 2300);
DISPLAY INVISIBLE (-5500 2300);
FORCEPROP 1 LAST PATH I122
R 1
J 0
(-5425 2350);
DISPLAY 0.872340 (-5425 2350);
PAINT AQUA (-5425 2350);
DISPLAY INVISIBLE (-5425 2350);
FORCEADD BSS138DW7F..1
(-5050 2225);
FORCEPROP 1 LAST LOCATION Q27
J 0
(-5200 2430);
DISPLAY 0.489362 (-5200 2430);
PAINT SKYBLUE (-5200 2430);
FORCEPROP 0 LAST $SEC 1
J 0
(-5175 2575);
DISPLAY 0.680851 (-5175 2575);
PAINT MONO (-5175 2575);
DISPLAY INVISIBLE (-5175 2575);
FORCEPROP 0 LAST CDS_SEC 1
J 0
(-5175 2575);
DISPLAY 0.680851 (-5175 2575);
DISPLAY INVISIBLE (-5175 2575);
FORCEPROP 0 LASTPIN (-5350 2175) $PN 6
J 2
(-5360 2185);
DISPLAY 0.489362 (-5360 2185);
PAINT MONO (-5360 2185);
FORCEPROP 0 LASTPIN (-4750 2175) $PN 3
J 0
(-4740 2185);
DISPLAY 0.489362 (-4740 2185);
PAINT MONO (-4740 2185);
FORCEPROP 0 LASTPIN (-5350 2225) $PN 2
J 2
(-5360 2235);
DISPLAY 0.489362 (-5360 2235);
PAINT MONO (-5360 2235);
FORCEPROP 0 LASTPIN (-4750 2225) $PN 5
J 0
(-4740 2235);
DISPLAY 0.489362 (-4740 2235);
PAINT MONO (-4740 2235);
FORCEPROP 0 LASTPIN (-5350 2275) $PN 1
J 2
(-5360 2285);
DISPLAY 0.489362 (-5360 2285);
PAINT MONO (-5360 2285);
FORCEPROP 0 LASTPIN (-4750 2275) $PN 4
J 0
(-4740 2285);
DISPLAY 0.489362 (-4740 2285);
PAINT MONO (-4740 2285);
FORCEPROP 1 LAST MATERIAL IC
J 0
(-5200 2335);
DISPLAY 0.489362 (-5200 2335);
PAINT SKYBLUE (-5200 2335);
FORCEPROP 2 LAST PART_TYPE SMLF
J 0
(-5175 2525);
DISPLAY 0.680851 (-5175 2525);
FORCEPROP 2 LAST VALUE BSS138DW-7-F
J 0
(-5175 2475);
DISPLAY 0.489362 (-5175 2475);
PAINT SKYBLUE (-5175 2475);
FORCEPROP 1 LAST PART_NUMBER BAM01380032
J 0
(-5200 2385);
DISPLAY 0.489362 (-5200 2385);
PAINT SKYBLUE (-5200 2385);
DISPLAY INVISIBLE (-5200 2385);
FORCEPROP 2 LAST CDS_LIB pure_quanta
J 0
(-5050 2225);
DISPLAY INVISIBLE (-5050 2225);
FORCEPROP 1 LAST NEEDS_NO_SIZE TRUE
J 0
(-5050 2225);
DISPLAY 0.468085 (-5050 2225);
PAINT GREEN (-5050 2225);
DISPLAY INVISIBLE (-5050 2225);
FORCEPROP 1 LAST PATH I123
J 0
(-4925 2330);
DISPLAY 0.723404 (-4925 2330);
PAINT GREEN (-4925 2330);
DISPLAY INVISIBLE (-4925 2330);
FORCEADD UNIVERSAL_GND..1
R 1
(-4675 2275);
FORCEPROP 3 LASTPIN (-4725 2275) SIG_NAME GND\g
J 0
(-4715 2285);
DISPLAY 0.659574 (-4715 2285);
PAINT MONO (-4715 2285);
DISPLAY INVISIBLE (-4715 2285);
FORCEPROP 2 LAST BOM_COST VR_SYSTEM
R 1
J 0
(-4750 1950);
DISPLAY 0.617021 (-4750 1950);
PAINT PURPLE (-4750 1950);
DISPLAY INVISIBLE (-4750 1950);
FORCEPROP 2 LAST CDS_LIB pure_quanta_power
J 0
(-4675 2275);
DISPLAY INVISIBLE (-4675 2275);
FORCEPROP 1 LAST HDL_POWER GND
R 1
J 1
(-4600 2300);
DISPLAY 0.872340 (-4600 2300);
PAINT GREEN (-4600 2300);
DISPLAY INVISIBLE (-4600 2300);
FORCEPROP 1 LAST PATH I124
R 1
J 0
(-4675 2350);
DISPLAY 0.872340 (-4675 2350);
PAINT AQUA (-4675 2350);
DISPLAY INVISIBLE (-4675 2350);
FORCEADD Q_RES..2
(-4600 2850);
FORCEPROP 1 LAST LOCATION R1493
J 0
(-4555 2975);
DISPLAY 0.617021 (-4555 2975);
PAINT SKYBLUE (-4555 2975);
FORCEPROP 0 LAST $SEC 1
J 0
(-4550 3025);
DISPLAY 0.680851 (-4550 3025);
PAINT MONO (-4550 3025);
DISPLAY INVISIBLE (-4550 3025);
FORCEPROP 0 LAST CDS_SEC 1
J 0
(-4550 3025);
DISPLAY 0.680851 (-4550 3025);
DISPLAY INVISIBLE (-4550 3025);
FORCEPROP 1 LASTPIN (-4600 2950) $PN 1
J 0
(-4595 2912);
DISPLAY 0.489362 (-4595 2912);
PAINT MONO (-4595 2912);
FORCEPROP 1 LASTPIN (-4600 2750) $PN 2
J 0
(-4595 2760);
DISPLAY 0.489362 (-4595 2760);
PAINT MONO (-4595 2760);
FORCEPROP 1 LAST PACK_TYPE 0402LF
J 0
(-4560 2675);
DISPLAY 0.489362 (-4560 2675);
PAINT SKYBLUE (-4560 2675);
FORCEPROP 1 LAST MATERIAL CHIP
J 0
(-4560 2775);
DISPLAY 0.489362 (-4560 2775);
PAINT SKYBLUE (-4560 2775);
FORCEPROP 1 LAST WATTAGE 1/16W
J 0
(-4560 2825);
DISPLAY 0.489362 (-4560 2825);
PAINT SKYBLUE (-4560 2825);
FORCEPROP 1 LAST TOLERANCE 5%
J 0
(-4555 2875);
DISPLAY 0.489362 (-4555 2875);
PAINT SKYBLUE (-4555 2875);
FORCEPROP 1 LAST VALUE 10K
J 0
(-4555 2925);
DISPLAY 0.489362 (-4555 2925);
PAINT SKYBLUE (-4555 2925);
FORCEPROP 1 LAST PART_NUMBER CS31002JB08
J 0
(-4560 2725);
DISPLAY 0.489362 (-4560 2725);
PAINT SKYBLUE (-4560 2725);
DISPLAY INVISIBLE (-4560 2725);
FORCEPROP 2 LAST BOM_COST VR_SYSTEM
J 0
(-4550 3025);
DISPLAY 0.680851 (-4550 3025);
DISPLAY INVISIBLE (-4550 3025);
FORCEPROP 2 LAST CDS_LIB pure_quanta
J 0
(-4600 2850);
DISPLAY INVISIBLE (-4600 2850);
FORCEPROP 1 LAST PATH I125
J 0
(-4550 3025);
DISPLAY 0.978723 (-4550 3025);
PAINT WHITE (-4550 3025);
DISPLAY INVISIBLE (-4550 3025);
FORCEADD P1V0_AUX..1
(-4600 3125);
FORCEPROP 3 LASTPIN (-4600 3075) SIG_NAME P1V8_AUX\g
J 0
(-4590 3085);
DISPLAY 0.659574 (-4590 3085);
PAINT MONO (-4590 3085);
DISPLAY INVISIBLE (-4590 3085);
FORCEPROP 1 LAST HDL_POWER P1V8_AUX
J 1
(-4590 3165);
DISPLAY 0.489362 (-4590 3165);
PAINT GREEN (-4590 3165);
FORCEPROP 2 LAST CDS_LIB pure_quanta_power
J 0
(-4600 3125);
DISPLAY INVISIBLE (-4600 3125);
FORCEPROP 1 LAST PATH I126
J 0
(-4550 3150);
DISPLAY 0.872340 (-4550 3150);
PAINT AQUA (-4550 3150);
DISPLAY INVISIBLE (-4550 3150);
FORCEADD OFFPAGE..2
(-3275 2600);
FORCEPROP 2 LAST $XR0 81 
J 0
(-3086 2600);
DISPLAY 0.638298 (-3086 2600);
PAINT MONO (-3086 2600);
FORCEPROP 2 LAST CDS_LIB standard
J 0
(-3275 2600);
DISPLAY INVISIBLE (-3275 2600);
FORCEPROP 1 LAST OFFPAGE TRUE
J 0
(-2950 2475);
DISPLAY 0.872340 (-2950 2475);
PAINT GREEN (-2950 2475);
DISPLAY INVISIBLE (-2950 2475);
FORCEPROP 1 LAST COMMENT_BODY TRUE
J 0
(-3320 2505);
DISPLAY 0.872340 (-3320 2505);
PAINT GREEN (-3320 2505);
DISPLAY INVISIBLE (-3320 2505);
FORCEPROP 2 LAST PATH I127
J 0
(-3075 2650);
DISPLAY 0.680851 (-3075 2650);
DISPLAY INVISIBLE (-3075 2650);
FORCEADD UNIVERSAL_GND..1
(-4350 4775);
FORCEPROP 3 LASTPIN (-4350 4825) SIG_NAME GND\g
J 0
(-4340 4835);
DISPLAY 0.659574 (-4340 4835);
PAINT MONO (-4340 4835);
DISPLAY INVISIBLE (-4340 4835);
FORCEPROP 0 LAST VOLTAGE 0
J 0
(-4350 4775);
PAINT SKYBLUE (-4350 4775);
DISPLAY INVISIBLE (-4350 4775);
FORCEPROP 2 LAST CDS_LIB pure_quanta_power
J 0
(-4350 4775);
DISPLAY INVISIBLE (-4350 4775);
FORCEPROP 2 LAST BOM_COST VR_SYSTEM 
J 0
(-4650 4850);
DISPLAY 0.680851 (-4650 4850);
DISPLAY INVISIBLE (-4650 4850);
FORCEPROP 1 LAST HDL_POWER GND
J 1
(-4325 4700);
DISPLAY 0.872340 (-4325 4700);
PAINT GREEN (-4325 4700);
DISPLAY INVISIBLE (-4325 4700);
FORCEPROP 1 LAST PATH I13
J 0
(-4275 4775);
DISPLAY 0.872340 (-4275 4775);
PAINT AQUA (-4275 4775);
DISPLAY INVISIBLE (-4275 4775);
FORCEADD Q_RES..1
(-3925 2600);
FORCEPROP 1 LAST LOCATION R1362
J 0
(-3825 2600);
DISPLAY 0.489362 (-3825 2600);
PAINT SKYBLUE (-3825 2600);
FORCEPROP 0 LAST $SEC 1
J 0
(-3825 2650);
DISPLAY 0.680851 (-3825 2650);
PAINT MONO (-3825 2650);
DISPLAY INVISIBLE (-3825 2650);
FORCEPROP 0 LAST CDS_SEC 1
J 0
(-3825 2650);
DISPLAY 0.680851 (-3825 2650);
DISPLAY INVISIBLE (-3825 2650);
FORCEPROP 1 LASTPIN (-4025 2600) $PN 1
J 0
(-4013 2612);
DISPLAY 0.489362 (-4013 2612);
PAINT MONO (-4013 2612);
FORCEPROP 1 LASTPIN (-3825 2600) $PN 2
J 0
(-3863 2612);
DISPLAY 0.489362 (-3863 2612);
PAINT MONO (-3863 2612);
FORCEPROP 1 LAST VALUE 33
J 2
(-4050 2600);
DISPLAY 0.489362 (-4050 2600);
PAINT SKYBLUE (-4050 2600);
FORCEPROP 1 LAST PART_NUMBER CS03302JB10
J 2
(-3825 2650);
DISPLAY 0.489362 (-3825 2650);
PAINT SKYBLUE (-3825 2650);
DISPLAY INVISIBLE (-3825 2650);
FORCEPROP 2 LAST CDS_LIB pure_quanta
J 0
(-3925 2600);
DISPLAY INVISIBLE (-3925 2600);
FORCEPROP 2 LAST BOM_COST MEM
J 2
(-3900 2750);
DISPLAY 0.744681 (-3900 2750);
PAINT WHITE (-3900 2750);
DISPLAY INVISIBLE (-3900 2750);
FORCEPROP 1 LAST WATTAGE 1/16W
J 2
(-4000 2525);
DISPLAY 0.489362 (-4000 2525);
PAINT SKYBLUE (-4000 2525);
DISPLAY INVISIBLE (-4000 2525);
FORCEPROP 1 LAST MATERIAL CHIP
J 2
(-3750 2575);
DISPLAY 0.489362 (-3750 2575);
PAINT SKYBLUE (-3750 2575);
DISPLAY INVISIBLE (-3750 2575);
FORCEPROP 1 LAST TOLERANCE 5%
J 0
(-4050 2575);
DISPLAY 0.489362 (-4050 2575);
PAINT SKYBLUE (-4050 2575);
DISPLAY INVISIBLE (-4050 2575);
FORCEPROP 1 LAST PACK_TYPE 0402LF
J 2
(-3750 2525);
DISPLAY 0.489362 (-3750 2525);
PAINT SKYBLUE (-3750 2525);
DISPLAY INVISIBLE (-3750 2525);
FORCEPROP 1 LAST PATH I130
J 0
(-3975 2750);
DISPLAY 0.978723 (-3975 2750);
PAINT WHITE (-3975 2750);
DISPLAY INVISIBLE (-3975 2750);
FORCEADD APX80929SAG7..1
R 2
(-7125 2325);
FORCEPROP 1 LAST LOCATION U6006
J 2
(-6900 2644);
DISPLAY 0.723404 (-6900 2644);
PAINT GREEN (-6900 2644);
FORCEPROP 2 LAST SEC 1
J 0
(-6900 2800);
DISPLAY 0.680851 (-6900 2800);
PAINT MONO (-6900 2800);
DISPLAY INVISIBLE (-6900 2800);
FORCEPROP 2 LASTPIN (-6750 2425) $PN 1
J 0
(-6740 2435);
DISPLAY 0.680851 (-6740 2435);
PAINT MONO (-6740 2435);
FORCEPROP 2 LASTPIN (-6750 2225) $PN 2
J 0
(-6740 2235);
DISPLAY 0.680851 (-6740 2235);
PAINT MONO (-6740 2235);
FORCEPROP 2 LASTPIN (-7500 2325) $PN 3
J 2
(-7510 2335);
DISPLAY 0.680851 (-7510 2335);
PAINT MONO (-7510 2335);
FORCEPROP 2 LAST VALUE APX809-29SAG-7
J 2
(-6900 2700);
DISPLAY 0.680851 (-6900 2700);
FORCEPROP 2 LAST PART_TYPE SMLF
J 2
(-6900 2750);
DISPLAY 0.680851 (-6900 2750);
FORCEPROP 1 LAST MATERIAL IC
J 2
(-6900 2535);
DISPLAY 0.723404 (-6900 2535);
PAINT GREEN (-6900 2535);
FORCEPROP 1 LAST PART_NUMBER AL080929000
J 2
(-6900 2592);
DISPLAY 0.723404 (-6900 2592);
PAINT GREEN (-6900 2592);
DISPLAY INVISIBLE (-6900 2592);
FORCEPROP 2 LAST CDS_LIB pure_quanta
J 2
(-7125 2325);
DISPLAY INVISIBLE (-7125 2325);
FORCEPROP 1 LAST NEEDS_NO_SIZE TRUE
J 2
(-7350 2165);
DISPLAY 0.723404 (-7350 2165);
PAINT GREEN (-7350 2165);
DISPLAY INVISIBLE (-7350 2165);
FORCEPROP 1 LAST CDS_LMAN_SYM_OUTLINE -225,200,225,-200
J 2
(-7125 2325);
DISPLAY 0.468085 (-7125 2325);
PAINT GREEN (-7125 2325);
DISPLAY INVISIBLE (-7125 2325);
FORCEPROP 2 LAST SEC_TYPE 
J 0
(-6900 2800);
DISPLAY 0.680851 (-6900 2800);
DISPLAY INVISIBLE (-6900 2800);
FORCEPROP 1 LAST PATH I131
J 2
(-7350 2125);
DISPLAY 0.723404 (-7350 2125);
PAINT GREEN (-7350 2125);
DISPLAY INVISIBLE (-7350 2125);
FORCEADD UNIVERSAL_POWER..1
(-7575 2625);
FORCEPROP 3 LASTPIN (-7575 2575) SIG_NAME P3V3\g
J 0
(-7565 2585);
DISPLAY 0.659574 (-7565 2585);
PAINT MONO (-7565 2585);
DISPLAY INVISIBLE (-7565 2585);
FORCEPROP 1 LAST HDL_POWER P3V3
J 1
(-7575 2675);
DISPLAY 0.489362 (-7575 2675);
PAINT GREEN (-7575 2675);
FORCEPROP 2 LAST BOM_COST VR_SYSTEM
J 0
(-7575 2725);
DISPLAY 0.617021 (-7575 2725);
PAINT PURPLE (-7575 2725);
DISPLAY INVISIBLE (-7575 2725);
FORCEPROP 2 LAST CDS_LIB pure_quanta_power
J 0
(-7575 2625);
DISPLAY INVISIBLE (-7575 2625);
FORCEPROP 1 LAST PATH I132
J 0
(-7525 2650);
DISPLAY 0.872340 (-7525 2650);
PAINT AQUA (-7525 2650);
DISPLAY INVISIBLE (-7525 2650);
FORCEADD Q_CAP..1
(-7575 2125);
FORCEPROP 1 LAST LOCATION C6500
J 0
(-7525 2225);
DISPLAY 0.808511 (-7525 2225);
FORCEPROP 0 LAST $SEC 1
J 0
(-7525 2275);
DISPLAY 0.680851 (-7525 2275);
PAINT MONO (-7525 2275);
DISPLAY INVISIBLE (-7525 2275);
FORCEPROP 0 LAST CDS_SEC 1
J 0
(-7525 2275);
DISPLAY 0.680851 (-7525 2275);
DISPLAY INVISIBLE (-7525 2275);
FORCEPROP 1 LASTPIN (-7575 2225) $PN 1
J 0
(-7565 2205);
DISPLAY 0.787234 (-7565 2205);
PAINT MONO (-7565 2205);
FORCEPROP 1 LASTPIN (-7575 2025) $PN 2
J 0
(-7565 2005);
DISPLAY 0.787234 (-7565 2005);
PAINT MONO (-7565 2005);
FORCEPROP 1 LAST MATERIAL X7R
J 0
(-7525 2025);
DISPLAY 0.638298 (-7525 2025);
FORCEPROP 1 LAST TOLERANCE 10%
J 0
(-7525 2075);
DISPLAY 0.638298 (-7525 2075);
FORCEPROP 1 LAST VALUE 0.1UF
J 0
(-7525 2175);
DISPLAY 0.638298 (-7525 2175);
FORCEPROP 1 LAST VOLTAGE 25V
J 0
(-7525 2125);
DISPLAY 0.638298 (-7525 2125);
FORCEPROP 1 LAST PACK_TYPE 0402
J 0
(-7525 1925);
DISPLAY 0.638298 (-7525 1925);
FORCEPROP 1 LAST PART_NUMBER CH4104K1B00
J 0
(-7525 1975);
DISPLAY 0.638298 (-7525 1975);
DISPLAY INVISIBLE (-7525 1975);
FORCEPROP 2 LAST CDS_LIB pure_quanta
J 0
(-7575 2125);
DISPLAY INVISIBLE (-7575 2125);
FORCEPROP 1 LAST PATH I133
J 0
(-7525 2275);
DISPLAY 0.978723 (-7525 2275);
PAINT WHITE (-7525 2275);
DISPLAY INVISIBLE (-7525 2275);
FORCEADD UNIVERSAL_GND..1
(-7575 1875);
FORCEPROP 3 LASTPIN (-7575 1925) SIG_NAME GND\g
J 0
(-7565 1935);
DISPLAY 0.659574 (-7565 1935);
PAINT MONO (-7565 1935);
DISPLAY INVISIBLE (-7565 1935);
FORCEPROP 2 LAST BOM_COST VR_SYSTEM 
J 0
(-7875 1950);
DISPLAY 0.680851 (-7875 1950);
DISPLAY INVISIBLE (-7875 1950);
FORCEPROP 0 LAST VOLTAGE 0
J 0
(-7575 1875);
PAINT SKYBLUE (-7575 1875);
DISPLAY INVISIBLE (-7575 1875);
FORCEPROP 2 LAST CDS_LIB pure_quanta_power
J 0
(-7575 1875);
DISPLAY INVISIBLE (-7575 1875);
FORCEPROP 1 LAST HDL_POWER GND
J 1
(-7550 1800);
DISPLAY 0.872340 (-7550 1800);
PAINT GREEN (-7550 1800);
DISPLAY INVISIBLE (-7550 1800);
FORCEPROP 1 LAST PATH I134
J 0
(-7500 1875);
DISPLAY 0.872340 (-7500 1875);
PAINT AQUA (-7500 1875);
DISPLAY INVISIBLE (-7500 1875);
FORCEADD UNIVERSAL_GND..1
(-6600 2325);
FORCEPROP 3 LASTPIN (-6600 2375) SIG_NAME GND\g
J 0
(-6590 2385);
DISPLAY 0.659574 (-6590 2385);
PAINT MONO (-6590 2385);
DISPLAY INVISIBLE (-6590 2385);
FORCEPROP 2 LAST CDS_LIB pure_quanta_power
J 0
(-6600 2325);
DISPLAY INVISIBLE (-6600 2325);
FORCEPROP 2 LAST BOM_COST VR_SYSTEM 
J 0
(-6900 2400);
DISPLAY 0.680851 (-6900 2400);
DISPLAY INVISIBLE (-6900 2400);
FORCEPROP 0 LAST VOLTAGE 0
J 0
(-6600 2325);
PAINT SKYBLUE (-6600 2325);
DISPLAY INVISIBLE (-6600 2325);
FORCEPROP 1 LAST HDL_POWER GND
J 1
(-6575 2250);
DISPLAY 0.872340 (-6575 2250);
PAINT GREEN (-6575 2250);
DISPLAY INVISIBLE (-6575 2250);
FORCEPROP 1 LAST PATH I135
J 0
(-6525 2325);
DISPLAY 0.872340 (-6525 2325);
PAINT AQUA (-6525 2325);
DISPLAY INVISIBLE (-6525 2325);
FORCEADD Q_RES..1
(-5950 2225);
FORCEPROP 1 LAST LOCATION R6500
J 0
(-6025 2275);
DISPLAY 0.638298 (-6025 2275);
FORCEPROP 2 LAST SEC 1
J 0
(-6000 2425);
DISPLAY 0.680851 (-6000 2425);
PAINT MONO (-6000 2425);
DISPLAY INVISIBLE (-6000 2425);
FORCEPROP 1 LASTPIN (-6050 2225) $PN 1
J 0
(-6038 2237);
DISPLAY 0.638298 (-6038 2237);
PAINT MONO (-6038 2237);
FORCEPROP 1 LASTPIN (-5850 2225) $PN 2
J 0
(-5888 2237);
DISPLAY 0.638298 (-5888 2237);
PAINT MONO (-5888 2237);
FORCEPROP 1 LAST PACK_TYPE 0402LF
J 0
(-6100 2125);
DISPLAY 0.510638 (-6100 2125);
FORCEPROP 1 LAST VALUE 0
J 2
(-6025 2175);
DISPLAY 0.510638 (-6025 2175);
FORCEPROP 1 LAST TOLERANCE 5%
J 0
(-5900 2175);
DISPLAY 0.510638 (-5900 2175);
FORCEPROP 1 LAST MATERIAL CHIP
J 0
(-5925 2125);
DISPLAY 0.510638 (-5925 2125);
FORCEPROP 1 LAST PART_NUMBER CS00002JB13
J 0
(-6100 2150);
DISPLAY 0.510638 (-6100 2150);
DISPLAY INVISIBLE (-6100 2150);
FORCEPROP 2 LAST SEC_TYPE 0402LF
J 0
(-6000 2425);
DISPLAY 0.680851 (-6000 2425);
DISPLAY INVISIBLE (-6000 2425);
FORCEPROP 2 LAST CDS_LIB pure_quanta
J 0
(-5950 2225);
DISPLAY INVISIBLE (-5950 2225);
FORCEPROP 1 LAST WATTAGE 1/16W
J 2
(-6075 2175);
DISPLAY 0.510638 (-6075 2175);
DISPLAY INVISIBLE (-6075 2175);
FORCEPROP 1 LAST PATH I136
J 0
(-6000 2375);
DISPLAY 0.978723 (-6000 2375);
PAINT WHITE (-6000 2375);
DISPLAY INVISIBLE (-6000 2375);
FORCEADD UNIVERSAL_POWER..1
(-6200 2775);
FORCEPROP 3 LASTPIN (-6200 2725) SIG_NAME P3V3\g
J 0
(-6190 2735);
DISPLAY 0.659574 (-6190 2735);
PAINT MONO (-6190 2735);
DISPLAY INVISIBLE (-6190 2735);
FORCEPROP 1 LAST HDL_POWER P3V3
J 1
(-6200 2825);
DISPLAY 0.489362 (-6200 2825);
PAINT GREEN (-6200 2825);
FORCEPROP 2 LAST CDS_LIB pure_quanta_power
J 0
(-6200 2775);
DISPLAY INVISIBLE (-6200 2775);
FORCEPROP 2 LAST BOM_COST VR_SYSTEM
J 0
(-6200 2875);
DISPLAY 0.617021 (-6200 2875);
PAINT PURPLE (-6200 2875);
DISPLAY INVISIBLE (-6200 2875);
FORCEPROP 1 LAST PATH I138
J 0
(-6150 2800);
DISPLAY 0.872340 (-6150 2800);
PAINT AQUA (-6150 2800);
DISPLAY INVISIBLE (-6150 2800);
FORCEADD Q_RES..2
R 2
(-6175 2050);
FORCEPROP 1 LAST LOCATION R6501
J 2
(-6220 2175);
DISPLAY 0.638298 (-6220 2175);
FORCEPROP 2 LAST SEC 1
J 0
(-6225 2275);
DISPLAY 0.680851 (-6225 2275);
PAINT MONO (-6225 2275);
DISPLAY INVISIBLE (-6225 2275);
FORCEPROP 1 LASTPIN (-6175 2150) $PN 1
J 2
(-6180 2112);
DISPLAY 0.787234 (-6180 2112);
PAINT MONO (-6180 2112);
FORCEPROP 1 LASTPIN (-6175 1950) $PN 2
J 2
(-6180 1960);
DISPLAY 0.787234 (-6180 1960);
PAINT MONO (-6180 1960);
FORCEPROP 1 LAST VALUE 100K
J 2
(-6220 2125);
DISPLAY 0.638298 (-6220 2125);
FORCEPROP 1 LAST MATERIAL CHIP
J 2
(-6225 2025);
DISPLAY 0.638298 (-6225 2025);
FORCEPROP 1 LAST TOLERANCE 1%
J 2
(-6220 2075);
DISPLAY 0.638298 (-6220 2075);
FORCEPROP 1 LAST PACK_TYPE 0402LF
J 2
(-6225 1925);
DISPLAY 0.638298 (-6225 1925);
FORCEPROP 1 LAST PART_NUMBER CS41002FB09
J 2
(-6225 1975);
DISPLAY 0.638298 (-6225 1975);
DISPLAY INVISIBLE (-6225 1975);
FORCEPROP 2 LAST SEC_TYPE 0402LF
J 0
(-6225 2275);
DISPLAY 0.680851 (-6225 2275);
DISPLAY INVISIBLE (-6225 2275);
FORCEPROP 2 LAST CDS_LIB pure_quanta
J 2
(-6175 2050);
DISPLAY INVISIBLE (-6175 2050);
FORCEPROP 1 LAST WATTAGE 1/16W
J 2
(-6215 2025);
DISPLAY 0.638298 (-6215 2025);
DISPLAY INVISIBLE (-6215 2025);
FORCEPROP 1 LAST PATH I139
J 2
(-6225 2225);
DISPLAY 0.978723 (-6225 2225);
PAINT WHITE (-6225 2225);
DISPLAY INVISIBLE (-6225 2225);
FORCEADD MOSFET_NCH_DUAL..2
(-4400 5325);
FORCEPROP 1 LAST LOCATION Q37
J 0
(-4249 5301);
DISPLAY 0.723404 (-4249 5301);
PAINT GREEN (-4249 5301);
FORCEPROP 2 LAST $SEC 2
J 0
(-4250 5475);
DISPLAY 0.680851 (-4250 5475);
PAINT MONO (-4250 5475);
DISPLAY INVISIBLE (-4250 5475);
FORCEPROP 2 LAST CDS_SEC 2
J 0
(-4250 5475);
DISPLAY 1.021277 (-4250 5475);
DISPLAY INVISIBLE (-4250 5475);
FORCEPROP 2 LASTPIN (-4350 5525) $PN 3
R 1
J 0
(-4360 5535);
DISPLAY 0.808511 (-4360 5535);
FORCEPROP 2 LASTPIN (-4600 5275) $PN 5
J 2
(-4610 5285);
DISPLAY 0.808511 (-4610 5285);
FORCEPROP 2 LASTPIN (-4350 5125) $PN 4
R 1
J 2
(-4360 5115);
DISPLAY 0.808511 (-4360 5115);
FORCEPROP 2 LAST VALUE PJT138K
J 0
(-4250 5375);
DISPLAY 0.808511 (-4250 5375);
FORCEPROP 1 LAST MATERIAL IC
J 0
(-4249 5176);
DISPLAY 0.723404 (-4249 5176);
PAINT GREEN (-4249 5176);
FORCEPROP 2 LAST PART_TYPE SMLF
J 0
(-4250 5425);
DISPLAY 0.808511 (-4250 5425);
FORCEPROP 1 LAST PART_NUMBER BAM138K0003
J 0
(-4249 5231);
DISPLAY 0.723404 (-4249 5231);
PAINT GREEN (-4249 5231);
DISPLAY INVISIBLE (-4249 5231);
FORCEPROP 1 LAST NEEDS_NO_SIZE TRUE
J 0
(-4250 5216);
DISPLAY 0.468085 (-4250 5216);
PAINT GREEN (-4250 5216);
DISPLAY INVISIBLE (-4250 5216);
FORCEPROP 1 LAST CDS_LMAN_SYM_OUTLINE -150,150,150,-150
J 0
(-4400 5325);
DISPLAY 0.468085 (-4400 5325);
PAINT GREEN (-4400 5325);
DISPLAY INVISIBLE (-4400 5325);
FORCEPROP 2 LAST CDS_LIB pure_quanta
J 0
(-4400 5325);
PAINT MONO (-4400 5325);
DISPLAY INVISIBLE (-4400 5325);
FORCEPROP 1 LAST PATH I14
J 0
(-4250 5175);
DISPLAY 0.723404 (-4250 5175);
PAINT GREEN (-4250 5175);
DISPLAY INVISIBLE (-4250 5175);
FORCEADD UNIVERSAL_GND..1
(-6175 1850);
FORCEPROP 3 LASTPIN (-6175 1900) SIG_NAME GND\g
J 0
(-6165 1910);
DISPLAY 0.659574 (-6165 1910);
PAINT MONO (-6165 1910);
DISPLAY INVISIBLE (-6165 1910);
FORCEPROP 2 LAST BOM_COST VR_SYSTEM 
J 0
(-6475 1925);
DISPLAY 0.680851 (-6475 1925);
DISPLAY INVISIBLE (-6475 1925);
FORCEPROP 0 LAST VOLTAGE 0
J 0
(-6175 1850);
PAINT SKYBLUE (-6175 1850);
DISPLAY INVISIBLE (-6175 1850);
FORCEPROP 2 LAST CDS_LIB pure_quanta_power
J 0
(-6175 1850);
DISPLAY INVISIBLE (-6175 1850);
FORCEPROP 1 LAST HDL_POWER GND
J 1
(-6150 1775);
DISPLAY 0.872340 (-6150 1775);
PAINT GREEN (-6150 1775);
DISPLAY INVISIBLE (-6150 1775);
FORCEPROP 1 LAST PATH I140
J 0
(-6100 1850);
DISPLAY 0.872340 (-6100 1850);
PAINT AQUA (-6100 1850);
DISPLAY INVISIBLE (-6100 1850);
FORCEADD Q_RES..2
(-6200 2550);
FORCEPROP 1 LAST LOCATION R1491
J 0
(-6155 2675);
DISPLAY 0.638298 (-6155 2675);
FORCEPROP 2 LAST SEC 1
J 0
(-6150 2775);
DISPLAY 0.680851 (-6150 2775);
PAINT MONO (-6150 2775);
DISPLAY INVISIBLE (-6150 2775);
FORCEPROP 1 LASTPIN (-6200 2650) $PN 1
J 0
(-6195 2612);
DISPLAY 0.787234 (-6195 2612);
PAINT MONO (-6195 2612);
FORCEPROP 1 LASTPIN (-6200 2450) $PN 2
J 0
(-6195 2460);
DISPLAY 0.787234 (-6195 2460);
PAINT MONO (-6195 2460);
FORCEPROP 1 LAST VALUE 10K
J 0
(-6155 2625);
DISPLAY 0.510638 (-6155 2625);
FORCEPROP 1 LAST TOLERANCE 5%
J 0
(-6155 2575);
DISPLAY 0.510638 (-6155 2575);
FORCEPROP 1 LAST PACK_TYPE 0402LF
J 0
(-6160 2375);
DISPLAY 0.510638 (-6160 2375);
FORCEPROP 1 LAST WATTAGE 1/16W
J 0
(-6160 2525);
DISPLAY 0.510638 (-6160 2525);
FORCEPROP 1 LAST MATERIAL EMPTY
J 0
(-6160 2475);
DISPLAY 0.510638 (-6160 2475);
FORCEPROP 1 LAST PART_NUMBER CS31002JB08
J 0
(-6160 2425);
DISPLAY 0.510638 (-6160 2425);
DISPLAY INVISIBLE (-6160 2425);
FORCEPROP 2 LAST SEC_TYPE 0402LF
J 0
(-6150 2775);
DISPLAY 0.680851 (-6150 2775);
DISPLAY INVISIBLE (-6150 2775);
FORCEPROP 2 LAST CDS_LIB pure_quanta
J 0
(-6200 2550);
DISPLAY INVISIBLE (-6200 2550);
FORCEPROP 1 LAST PATH I141
J 0
(-6150 2725);
DISPLAY 0.978723 (-6150 2725);
PAINT WHITE (-6150 2725);
DISPLAY INVISIBLE (-6150 2725);
FORCEADD Q_RES..1
(-5575 6625);
FORCEPROP 1 LAST LOCATION R335
J 0
(-5850 6625);
DISPLAY 0.638298 (-5850 6625);
FORCEPROP 2 LAST $SEC 1
J 0
(-5625 6825);
DISPLAY 0.680851 (-5625 6825);
PAINT MONO (-5625 6825);
DISPLAY INVISIBLE (-5625 6825);
FORCEPROP 2 LAST CDS_SEC 1
J 0
(-5625 6825);
DISPLAY 1.021277 (-5625 6825);
DISPLAY INVISIBLE (-5625 6825);
FORCEPROP 1 LASTPIN (-5675 6625) $PN 1
J 0
(-5663 6637);
DISPLAY 0.787234 (-5663 6637);
FORCEPROP 1 LASTPIN (-5475 6625) $PN 2
J 0
(-5513 6637);
DISPLAY 0.787234 (-5513 6637);
FORCEPROP 1 LAST TOLERANCE 1%
J 0
(-5350 6625);
DISPLAY 0.489362 (-5350 6625);
FORCEPROP 1 LAST PACK_TYPE 0402LF
J 0
(-5275 6625);
DISPLAY 0.489362 (-5275 6625);
FORCEPROP 1 LAST MATERIAL CHIP
J 0
(-5450 6525);
DISPLAY 0.489362 (-5450 6525);
FORCEPROP 1 LAST VALUE 10K
J 2
(-5375 6625);
DISPLAY 0.489362 (-5375 6625);
FORCEPROP 1 LAST WATTAGE 1/16W
J 2
(-5225 6525);
DISPLAY 0.489362 (-5225 6525);
FORCEPROP 1 LAST PART_NUMBER CS31002FB08
J 0
(-5450 6575);
DISPLAY 0.489362 (-5450 6575);
DISPLAY INVISIBLE (-5450 6575);
FORCEPROP 2 LAST CDS_LIB pure_quanta
J 0
(-5575 6625);
PAINT MONO (-5575 6625);
DISPLAY INVISIBLE (-5575 6625);
FORCEPROP 2 LAST BOM_COST VR_SYSTEM 
J 0
(-5775 6775);
DISPLAY 0.680851 (-5775 6775);
DISPLAY INVISIBLE (-5775 6775);
FORCEPROP 2 LAST REUSE_ID 3
J 0
(-5625 6825);
DISPLAY 0.680851 (-5625 6825);
DISPLAY INVISIBLE (-5625 6825);
FORCEPROP 1 LAST PATH I15
J 0
(-5625 6775);
DISPLAY 0.978723 (-5625 6775);
PAINT WHITE (-5625 6775);
DISPLAY INVISIBLE (-5625 6775);
FORCEADD UNIVERSAL_POWER..1
(-5975 6925);
FORCEPROP 3 LASTPIN (-5975 6875) SIG_NAME P12V_AUX\g
J 0
(-5965 6885);
DISPLAY 0.659574 (-5965 6885);
PAINT MONO (-5965 6885);
DISPLAY INVISIBLE (-5965 6885);
FORCEPROP 1 LAST HDL_POWER P12V_AUX
J 1
(-5975 6975);
DISPLAY 0.617021 (-5975 6975);
PAINT GREEN (-5975 6975);
FORCEPROP 2 LAST BOM_COST VR_SYSTEM 
J 0
(-5975 7025);
DISPLAY 0.680851 (-5975 7025);
DISPLAY INVISIBLE (-5975 7025);
FORCEPROP 2 LAST CDS_LIB pure_quanta_power
J 0
(-5975 6925);
PAINT RED (-5975 6925);
DISPLAY INVISIBLE (-5975 6925);
FORCEPROP 1 LAST PATH I16
J 0
(-5925 6950);
DISPLAY 0.872340 (-5925 6950);
PAINT AQUA (-5925 6950);
DISPLAY INVISIBLE (-5925 6950);
FORCEADD UNIVERSAL_GND..1
(-5975 7225);
FORCEPROP 3 LASTPIN (-5975 7275) SIG_NAME GND\g
J 0
(-5965 7285);
DISPLAY 0.659574 (-5965 7285);
PAINT MONO (-5965 7285);
DISPLAY INVISIBLE (-5965 7285);
FORCEPROP 2 LAST BOM_COST VR_SYSTEM 
J 0
(-6275 7300);
DISPLAY 0.680851 (-6275 7300);
DISPLAY INVISIBLE (-6275 7300);
FORCEPROP 2 LAST CDS_LIB pure_quanta_power
J 0
(-5975 7225);
DISPLAY INVISIBLE (-5975 7225);
FORCEPROP 0 LAST VOLTAGE 0
J 0
(-5975 7225);
PAINT SKYBLUE (-5975 7225);
DISPLAY INVISIBLE (-5975 7225);
FORCEPROP 1 LAST HDL_POWER GND
J 1
(-5950 7150);
DISPLAY 0.872340 (-5950 7150);
PAINT GREEN (-5950 7150);
DISPLAY INVISIBLE (-5950 7150);
FORCEPROP 1 LAST PATH I17
J 0
(-5900 7225);
DISPLAY 0.872340 (-5900 7225);
PAINT AQUA (-5900 7225);
DISPLAY INVISIBLE (-5900 7225);
FORCEADD Q_CAP..1
R 2
(-5975 7575);
FORCEPROP 1 LAST LOCATION C1042
J 2
(-6025 7675);
DISPLAY 0.978723 (-6025 7675);
FORCEPROP 2 LAST $SEC 1
J 0
(-6025 7775);
DISPLAY 0.680851 (-6025 7775);
PAINT MONO (-6025 7775);
DISPLAY INVISIBLE (-6025 7775);
FORCEPROP 2 LAST CDS_SEC 1
J 0
(-6025 7775);
DISPLAY 1.021277 (-6025 7775);
DISPLAY INVISIBLE (-6025 7775);
FORCEPROP 1 LASTPIN (-5975 7675) $PN 1
J 2
(-5985 7655);
DISPLAY 0.787234 (-5985 7655);
FORCEPROP 1 LASTPIN (-5975 7475) $PN 2
J 2
(-5985 7455);
DISPLAY 0.787234 (-5985 7455);
FORCEPROP 1 LAST PACK_TYPE C0402
J 2
(-6025 7375);
DISPLAY 0.489362 (-6025 7375);
FORCEPROP 1 LAST TOLERANCE 10%
J 2
(-6025 7525);
DISPLAY 0.489362 (-6025 7525);
FORCEPROP 1 LAST VALUE 100NF
J 2
(-6025 7625);
DISPLAY 0.489362 (-6025 7625);
FORCEPROP 1 LAST VOLTAGE 50V
J 2
(-6025 7575);
DISPLAY 0.489362 (-6025 7575);
FORCEPROP 1 LAST MATERIAL X7R
J 2
(-6025 7475);
DISPLAY 0.489362 (-6025 7475);
FORCEPROP 1 LAST PART_NUMBER CH4106K1B01
J 2
(-6025 7425);
DISPLAY 0.489362 (-6025 7425);
DISPLAY INVISIBLE (-6025 7425);
FORCEPROP 2 LAST CDS_LIB pure_quanta
J 0
(-5975 7575);
PAINT MONO (-5975 7575);
DISPLAY INVISIBLE (-5975 7575);
FORCEPROP 2 LAST BOM_COST VR_SYSTEM 
J 0
(-6025 7725);
DISPLAY 0.680851 (-6025 7725);
DISPLAY INVISIBLE (-6025 7725);
FORCEPROP 2 LAST REUSE_ID 81
J 0
(-6025 7775);
DISPLAY 0.680851 (-6025 7775);
DISPLAY INVISIBLE (-6025 7775);
FORCEPROP 1 LAST PATH I18
J 2
(-6025 7725);
DISPLAY 0.978723 (-6025 7725);
PAINT WHITE (-6025 7725);
DISPLAY INVISIBLE (-6025 7725);
FORCEADD Q_CAP..1
R 2
(-5650 7575);
FORCEPROP 1 LAST LOCATION C1170
J 2
(-5700 7675);
DISPLAY 0.978723 (-5700 7675);
FORCEPROP 2 LAST $SEC 1
J 0
(-5700 7775);
DISPLAY 0.680851 (-5700 7775);
PAINT MONO (-5700 7775);
DISPLAY INVISIBLE (-5700 7775);
FORCEPROP 2 LAST CDS_SEC 1
J 0
(-5700 7775);
DISPLAY 1.021277 (-5700 7775);
DISPLAY INVISIBLE (-5700 7775);
FORCEPROP 1 LASTPIN (-5650 7675) $PN 1
J 2
(-5660 7655);
DISPLAY 0.787234 (-5660 7655);
FORCEPROP 1 LASTPIN (-5650 7475) $PN 2
J 2
(-5660 7455);
DISPLAY 0.787234 (-5660 7455);
FORCEPROP 1 LAST VALUE 10UF
J 2
(-5700 7625);
DISPLAY 0.489362 (-5700 7625);
FORCEPROP 1 LAST PACK_TYPE C0805
J 2
(-5700 7375);
DISPLAY 0.489362 (-5700 7375);
FORCEPROP 1 LAST MATERIAL X6S
J 2
(-5700 7475);
DISPLAY 0.489362 (-5700 7475);
FORCEPROP 1 LAST TOLERANCE 10%
J 2
(-5700 7525);
DISPLAY 0.489362 (-5700 7525);
FORCEPROP 1 LAST VOLTAGE 16V
J 2
(-5700 7575);
DISPLAY 0.489362 (-5700 7575);
FORCEPROP 1 LAST PART_NUMBER CH6103KEA00
J 2
(-5700 7425);
DISPLAY 0.489362 (-5700 7425);
DISPLAY INVISIBLE (-5700 7425);
FORCEPROP 2 LAST CDS_LIB pure_quanta
J 0
(-5650 7575);
PAINT MONO (-5650 7575);
DISPLAY INVISIBLE (-5650 7575);
FORCEPROP 2 LAST BOM_COST VR_SYSTEM 
J 0
(-5700 7725);
DISPLAY 0.680851 (-5700 7725);
DISPLAY INVISIBLE (-5700 7725);
FORCEPROP 2 LAST REUSE_ID 6
J 0
(-5700 7775);
DISPLAY 0.680851 (-5700 7775);
DISPLAY INVISIBLE (-5700 7775);
FORCEPROP 1 LAST PATH I19
J 2
(-5700 7725);
DISPLAY 0.978723 (-5700 7725);
PAINT WHITE (-5700 7725);
DISPLAY INVISIBLE (-5700 7725);
FORCEADD Q_CAP..1
R 2
(-5325 7575);
FORCEPROP 1 LAST LOCATION C57
J 2
(-5375 7675);
DISPLAY 0.978723 (-5375 7675);
FORCEPROP 2 LAST $SEC 1
J 0
(-5375 7775);
DISPLAY 0.680851 (-5375 7775);
PAINT MONO (-5375 7775);
DISPLAY INVISIBLE (-5375 7775);
FORCEPROP 2 LAST CDS_SEC 1
J 0
(-5375 7775);
DISPLAY 1.021277 (-5375 7775);
DISPLAY INVISIBLE (-5375 7775);
FORCEPROP 1 LASTPIN (-5325 7675) $PN 1
J 2
(-5335 7655);
DISPLAY 0.787234 (-5335 7655);
FORCEPROP 1 LASTPIN (-5325 7475) $PN 2
J 2
(-5335 7455);
DISPLAY 0.787234 (-5335 7455);
FORCEPROP 1 LAST TOLERANCE 10%
J 2
(-5375 7525);
DISPLAY 0.489362 (-5375 7525);
FORCEPROP 1 LAST MATERIAL EMPTY
J 2
(-5375 7475);
DISPLAY 0.489362 (-5375 7475);
PAINT RED (-5375 7475);
FORCEPROP 1 LAST VALUE 10UF
J 2
(-5375 7625);
DISPLAY 0.489362 (-5375 7625);
FORCEPROP 1 LAST VOLTAGE 16V
J 2
(-5375 7575);
DISPLAY 0.489362 (-5375 7575);
FORCEPROP 1 LAST PACK_TYPE C0805
J 2
(-5375 7375);
DISPLAY 0.489362 (-5375 7375);
FORCEPROP 1 LAST PART_NUMBER CH6103KEA00
J 2
(-5375 7425);
DISPLAY 0.489362 (-5375 7425);
DISPLAY INVISIBLE (-5375 7425);
FORCEPROP 2 LAST CDS_LIB pure_quanta
J 0
(-5325 7575);
PAINT MONO (-5325 7575);
DISPLAY INVISIBLE (-5325 7575);
FORCEPROP 2 LAST BOM_COST VR_SYSTEM 
J 0
(-5375 7725);
DISPLAY 0.680851 (-5375 7725);
DISPLAY INVISIBLE (-5375 7725);
FORCEPROP 2 LAST REUSE_ID 8
J 0
(-5375 7775);
DISPLAY 0.680851 (-5375 7775);
DISPLAY INVISIBLE (-5375 7775);
FORCEPROP 1 LAST PATH I20
J 2
(-5375 7725);
DISPLAY 0.978723 (-5375 7725);
PAINT WHITE (-5375 7725);
DISPLAY INVISIBLE (-5375 7725);
FORCEADD P1V0_AUX..1
(-5151 7874);
FORCEPROP 3 LASTPIN (-5151 7824) SIG_NAME P5V_AUX\g
J 0
(-5141 7834);
DISPLAY 0.659574 (-5141 7834);
PAINT MONO (-5141 7834);
DISPLAY INVISIBLE (-5141 7834);
FORCEPROP 1 LAST HDL_POWER P5V_AUX
J 1
(-5141 7914);
DISPLAY 0.617021 (-5141 7914);
PAINT GREEN (-5141 7914);
FORCEPROP 2 LAST BOM_COST VR_SYSTEM 
J 0
(-5125 7950);
DISPLAY 0.680851 (-5125 7950);
DISPLAY INVISIBLE (-5125 7950);
FORCEPROP 2 LAST CDS_LIB pure_quanta_power
J 0
(-5151 7874);
PAINT RED (-5151 7874);
DISPLAY INVISIBLE (-5151 7874);
FORCEPROP 1 LAST PATH I21
J 0
(-5101 7899);
DISPLAY 0.872340 (-5101 7899);
PAINT AQUA (-5101 7899);
DISPLAY INVISIBLE (-5101 7899);
FORCEADD Q_RES..2
(-4350 6325);
FORCEPROP 1 LAST LOCATION R1654
J 0
(-4600 6450);
DISPLAY 0.978723 (-4600 6450);
FORCEPROP 2 LAST $SEC 1
J 0
(-4300 6550);
DISPLAY 0.680851 (-4300 6550);
PAINT MONO (-4300 6550);
DISPLAY INVISIBLE (-4300 6550);
FORCEPROP 2 LAST CDS_SEC 1
J 0
(-4300 6550);
DISPLAY 1.021277 (-4300 6550);
DISPLAY INVISIBLE (-4300 6550);
FORCEPROP 1 LASTPIN (-4350 6425) $PN 1
J 0
(-4345 6387);
DISPLAY 0.787234 (-4345 6387);
FORCEPROP 1 LASTPIN (-4350 6225) $PN 2
J 0
(-4345 6235);
DISPLAY 0.787234 (-4345 6235);
FORCEPROP 1 LAST WATTAGE 1/16W
J 2
(-4400 6300);
DISPLAY 0.617021 (-4400 6300);
FORCEPROP 1 LAST MATERIAL CHIP
J 2
(-4400 6250);
DISPLAY 0.617021 (-4400 6250);
FORCEPROP 1 LAST VALUE 1K
J 2
(-4400 6400);
DISPLAY 0.617021 (-4400 6400);
FORCEPROP 1 LAST PACK_TYPE 0402LF
J 2
(-4400 6150);
DISPLAY 0.617021 (-4400 6150);
FORCEPROP 1 LAST TOLERANCE 1%
J 2
(-4400 6350);
DISPLAY 0.617021 (-4400 6350);
FORCEPROP 1 LAST PART_NUMBER CS21002FB06
J 2
(-4400 6200);
DISPLAY 0.617021 (-4400 6200);
DISPLAY INVISIBLE (-4400 6200);
FORCEPROP 2 LAST BOM_COST VR_SYSTEM 
J 0
(-4400 6475);
DISPLAY 0.680851 (-4400 6475);
DISPLAY INVISIBLE (-4400 6475);
FORCEPROP 2 LAST REUSE_ID 3
J 0
(-4400 6525);
DISPLAY 0.680851 (-4400 6525);
DISPLAY INVISIBLE (-4400 6525);
FORCEPROP 2 LAST CDS_LIB pure_quanta
J 0
(-4350 6325);
PAINT MONO (-4350 6325);
DISPLAY INVISIBLE (-4350 6325);
FORCEPROP 1 LAST PATH I22
J 0
(-4300 6500);
DISPLAY 0.978723 (-4300 6500);
PAINT WHITE (-4300 6500);
DISPLAY INVISIBLE (-4300 6500);
FORCEADD MOSFET_NCH_1D3S..1
R 7
(-4000 6900);
FORCEPROP 1 LAST LOCATION Q57
J 0
(-4168 7077);
DISPLAY 0.723404 (-4168 7077);
PAINT GREEN (-4168 7077);
FORCEPROP 2 LAST $SEC 1
J 0
(-4200 7375);
DISPLAY 0.680851 (-4200 7375);
PAINT MONO (-4200 7375);
DISPLAY INVISIBLE (-4200 7375);
FORCEPROP 2 LAST CDS_SEC 1
J 0
(-4200 7375);
DISPLAY 1.021277 (-4200 7375);
DISPLAY INVISIBLE (-4200 7375);
FORCEPROP 2 LASTPIN (-3750 7000) $PN 1
J 0
(-3740 7010);
DISPLAY 0.808511 (-3740 7010);
FORCEPROP 2 LASTPIN (-3750 6900) $PN 2
J 0
(-3740 6910);
DISPLAY 0.808511 (-3740 6910);
FORCEPROP 2 LASTPIN (-3750 6800) $PN 3
J 0
(-3740 6810);
DISPLAY 0.808511 (-3740 6810);
FORCEPROP 2 LASTPIN (-3950 6700) $PN 4
R 1
J 2
(-3960 6690);
DISPLAY 0.808511 (-3960 6690);
FORCEPROP 2 LASTPIN (-4250 6900) $PN 5
J 2
(-4260 6910);
DISPLAY 0.808511 (-4260 6910);
FORCEPROP 2 LAST VALUE PSMNR58-30YLH
J 0
(-4200 7250);
DISPLAY 0.808511 (-4200 7250);
FORCEPROP 2 LAST PART_TYPE SMLF
J 0
(-4200 7325);
DISPLAY 0.808511 (-4200 7325);
FORCEPROP 1 LAST MATERIAL IC
J 0
(-4184 7127);
DISPLAY 0.723404 (-4184 7127);
PAINT GREEN (-4184 7127);
FORCEPROP 1 LAST PART_NUMBER BAMNR580000
J 0
(-4200 7177);
DISPLAY 0.723404 (-4200 7177);
PAINT GREEN (-4200 7177);
DISPLAY INVISIBLE (-4200 7177);
FORCEPROP 1 LAST NEEDS_NO_SIZE TRUE
R 1
J 0
(-4001 6900);
DISPLAY 0.468085 (-4001 6900);
PAINT GREEN (-4001 6900);
DISPLAY INVISIBLE (-4001 6900);
FORCEPROP 1 LAST CDS_LMAN_SYM_OUTLINE -150,200,150,-200
R 1
J 0
(-4000 6900);
DISPLAY 0.468085 (-4000 6900);
PAINT GREEN (-4000 6900);
DISPLAY INVISIBLE (-4000 6900);
FORCEPROP 2 LAST CDS_LIB pure_quanta
J 0
(-4000 6900);
PAINT MONO (-4000 6900);
DISPLAY INVISIBLE (-4000 6900);
FORCEPROP 1 LAST PATH I23
R 1
J 0
(-4000 6900);
DISPLAY 0.723404 (-4000 6900);
PAINT GREEN (-4000 6900);
DISPLAY INVISIBLE (-4000 6900);
FORCEADD UNIVERSAL_POWER..1
(-7225 3900);
FORCEPROP 3 LASTPIN (-7225 3850) SIG_NAME P3V3\g
J 0
(-7215 3860);
DISPLAY 0.659574 (-7215 3860);
PAINT MONO (-7215 3860);
DISPLAY INVISIBLE (-7215 3860);
FORCEPROP 1 LAST HDL_POWER P3V3
J 1
(-7225 3950);
DISPLAY 0.617021 (-7225 3950);
PAINT GREEN (-7225 3950);
FORCEPROP 2 LAST BOM_COST VR_SYSTEM 
J 0
(-7225 4000);
DISPLAY 0.680851 (-7225 4000);
DISPLAY INVISIBLE (-7225 4000);
FORCEPROP 2 LAST CDS_LIB pure_quanta_power
J 0
(-7225 3900);
PAINT RED (-7225 3900);
DISPLAY INVISIBLE (-7225 3900);
FORCEPROP 1 LAST PATH I26
J 0
(-7175 3925);
DISPLAY 0.872340 (-7175 3925);
PAINT AQUA (-7175 3925);
DISPLAY INVISIBLE (-7175 3925);
FORCEADD BAT547F..1
(-6775 3625);
FORCEPROP 1 LAST LOCATION D1
J 0
(-6850 3785);
DISPLAY 0.723404 (-6850 3785);
PAINT GREEN (-6850 3785);
FORCEPROP 2 LAST $SEC 1
J 0
(-6850 3975);
DISPLAY 0.680851 (-6850 3975);
PAINT MONO (-6850 3975);
DISPLAY INVISIBLE (-6850 3975);
FORCEPROP 2 LAST CDS_SEC 1
J 0
(-6850 3975);
DISPLAY 1.021277 (-6850 3975);
DISPLAY INVISIBLE (-6850 3975);
FORCEPROP 2 LASTPIN (-6900 3625) $PN 1
J 2
(-6910 3635);
DISPLAY 0.808511 (-6910 3635);
FORCEPROP 2 LASTPIN (-6650 3625) $PN 3
J 0
(-6640 3635);
DISPLAY 0.808511 (-6640 3635);
FORCEPROP 2 LAST VALUE BAT547F
J 0
(-6850 3875);
DISPLAY 0.617021 (-6850 3875);
PAINT GREEN (-6850 3875);
FORCEPROP 1 LAST MATERIAL IC
J 0
(-6850 3705);
DISPLAY 0.617021 (-6850 3705);
PAINT GREEN (-6850 3705);
FORCEPROP 2 LAST PART_TYPE SMLF
J 0
(-6850 3925);
DISPLAY 0.680851 (-6850 3925);
PAINT GREEN (-6850 3925);
FORCEPROP 1 LAST PART_NUMBER BC0BAT54Z53
J 0
(-6850 3760);
DISPLAY 0.617021 (-6850 3760);
PAINT GREEN (-6850 3760);
DISPLAY INVISIBLE (-6850 3760);
FORCEPROP 1 LAST PIN_NAMES_ROTATE TRUE
J 0
(-6850 3550);
DISPLAY 0.234043 (-6850 3550);
PAINT GREEN (-6850 3550);
DISPLAY INVISIBLE (-6850 3550);
FORCEPROP 1 LAST NEEDS_NO_SIZE TRUE
J 0
(-6775 3625);
DISPLAY 0.468085 (-6775 3625);
PAINT GREEN (-6775 3625);
DISPLAY INVISIBLE (-6775 3625);
FORCEPROP 2 LAST BOM_COST VR_SYSTEM 
J 0
(-6850 3925);
DISPLAY 0.680851 (-6850 3925);
DISPLAY INVISIBLE (-6850 3925);
FORCEPROP 1 LAST CDS_LMAN_SYM_OUTLINE -25,50,25,-50
J 0
(-6775 3625);
DISPLAY 0.468085 (-6775 3625);
PAINT GREEN (-6775 3625);
DISPLAY INVISIBLE (-6775 3625);
FORCEPROP 2 LAST CDS_LIB pure_quanta
J 0
(-6775 3625);
PAINT MONO (-6775 3625);
DISPLAY INVISIBLE (-6775 3625);
FORCEPROP 1 LAST PATH I27
J 0
(-6725 3680);
DISPLAY 0.723404 (-6725 3680);
PAINT GREEN (-6725 3680);
DISPLAY INVISIBLE (-6725 3680);
FORCEADD UNIVERSAL_POWER..1
(-6250 3900);
FORCEPROP 3 LASTPIN (-6250 3850) SIG_NAME P5V\g
J 0
(-6240 3860);
DISPLAY 0.659574 (-6240 3860);
PAINT MONO (-6240 3860);
DISPLAY INVISIBLE (-6240 3860);
FORCEPROP 1 LAST HDL_POWER P5V
J 1
(-6250 3950);
DISPLAY 0.617021 (-6250 3950);
PAINT GREEN (-6250 3950);
FORCEPROP 2 LAST BOM_COST VR_SYSTEM 
J 0
(-6250 4000);
DISPLAY 0.680851 (-6250 4000);
DISPLAY INVISIBLE (-6250 4000);
FORCEPROP 2 LAST CDS_LIB pure_quanta_power
J 0
(-6250 3900);
PAINT RED (-6250 3900);
DISPLAY INVISIBLE (-6250 3900);
FORCEPROP 1 LAST PATH I28
J 0
(-6200 3925);
DISPLAY 0.872340 (-6200 3925);
PAINT AQUA (-6200 3925);
DISPLAY INVISIBLE (-6200 3925);
FORCEADD OFFPAGE..1
(-7150 4950);
FORCEPROP 2 LAST $XR0 81 
J 0
(-7371 4950);
DISPLAY 0.638298 (-7371 4950);
PAINT MONO (-7371 4950);
FORCEPROP 2 LAST CDS_LIB standard
J 0
(-7150 4950);
DISPLAY INVISIBLE (-7150 4950);
FORCEPROP 2 LAST BOM_COST VR_SYSTEM 
J 0
(-7425 5000);
DISPLAY 0.617021 (-7425 5000);
PAINT PURPLE (-7425 5000);
DISPLAY INVISIBLE (-7425 5000);
FORCEPROP 1 LAST OFFPAGE TRUE
J 0
(-6825 4825);
DISPLAY 1.042553 (-6825 4825);
PAINT GREEN (-6825 4825);
DISPLAY INVISIBLE (-6825 4825);
FORCEPROP 1 LAST COMMENT_BODY TRUE
J 0
(-7025 4850);
DISPLAY 1.042553 (-7025 4850);
PAINT GREEN (-7025 4850);
DISPLAY INVISIBLE (-7025 4850);
FORCEPROP 2 LAST PATH I3
J 0
(-7400 5000);
DISPLAY 0.680851 (-7400 5000);
DISPLAY INVISIBLE (-7400 5000);
FORCEADD UNIVERSAL_GND..1
(-3950 6050);
FORCEPROP 3 LASTPIN (-3950 6100) SIG_NAME GND\g
J 0
(-3940 6110);
DISPLAY 0.659574 (-3940 6110);
PAINT MONO (-3940 6110);
DISPLAY INVISIBLE (-3940 6110);
FORCEPROP 2 LAST CDS_LIB pure_quanta_power
J 0
(-3950 6050);
DISPLAY INVISIBLE (-3950 6050);
FORCEPROP 0 LAST VOLTAGE 0
J 0
(-3950 6050);
PAINT SKYBLUE (-3950 6050);
DISPLAY INVISIBLE (-3950 6050);
FORCEPROP 2 LAST BOM_COST VR_SYSTEM 
J 0
(-4250 6125);
DISPLAY 0.680851 (-4250 6125);
DISPLAY INVISIBLE (-4250 6125);
FORCEPROP 1 LAST HDL_POWER GND
J 1
(-3925 5975);
DISPLAY 0.872340 (-3925 5975);
PAINT GREEN (-3925 5975);
DISPLAY INVISIBLE (-3925 5975);
FORCEPROP 1 LAST PATH I37
J 0
(-3875 6050);
DISPLAY 0.872340 (-3875 6050);
PAINT AQUA (-3875 6050);
DISPLAY INVISIBLE (-3875 6050);
FORCEADD Q_CAP..1
(-3950 6325);
FORCEPROP 1 LAST LOCATION C9226
J 0
(-3900 6425);
DISPLAY 0.617021 (-3900 6425);
FORCEPROP 0 LAST $SEC 1
J 0
(-3900 6475);
DISPLAY 0.680851 (-3900 6475);
PAINT MONO (-3900 6475);
DISPLAY INVISIBLE (-3900 6475);
FORCEPROP 0 LAST CDS_SEC 1
J 0
(-3900 6475);
DISPLAY 0.680851 (-3900 6475);
DISPLAY INVISIBLE (-3900 6475);
FORCEPROP 1 LASTPIN (-3950 6425) $PN 1
J 0
(-3940 6405);
DISPLAY 0.787234 (-3940 6405);
PAINT MONO (-3940 6405);
FORCEPROP 1 LASTPIN (-3950 6225) $PN 2
J 0
(-3940 6205);
DISPLAY 0.787234 (-3940 6205);
PAINT MONO (-3940 6205);
FORCEPROP 1 LAST TOLERANCE 10%
J 0
(-3900 6275);
DISPLAY 0.617021 (-3900 6275);
FORCEPROP 1 LAST VOLTAGE 25V
J 0
(-3900 6325);
DISPLAY 0.617021 (-3900 6325);
FORCEPROP 1 LAST PACK_TYPE C0402
J 0
(-3900 6125);
DISPLAY 0.617021 (-3900 6125);
FORCEPROP 1 LAST MATERIAL X7R
J 0
(-3900 6225);
DISPLAY 0.617021 (-3900 6225);
FORCEPROP 1 LAST VALUE 0.22UF
J 0
(-3900 6375);
DISPLAY 0.617021 (-3900 6375);
FORCEPROP 1 LAST PART_NUMBER CH4224K1B01
J 0
(-3900 6175);
DISPLAY 0.617021 (-3900 6175);
DISPLAY INVISIBLE (-3900 6175);
FORCEPROP 2 LAST CDS_LIB pure_quanta
J 0
(-3950 6325);
DISPLAY INVISIBLE (-3950 6325);
FORCEPROP 1 LAST PATH I38
J 0
(-3900 6475);
DISPLAY 0.978723 (-3900 6475);
PAINT WHITE (-3900 6475);
DISPLAY INVISIBLE (-3900 6475);
FORCEADD OFFPAGE..1
(-3125 6625);
FORCEPROP 2 LAST $XR0 188 
J 0
(-3377 6625);
DISPLAY 0.638298 (-3377 6625);
PAINT MONO (-3377 6625);
FORCEPROP 2 LAST BOM_COST VR_SYSTEM 
J 0
(-3400 6675);
DISPLAY 0.617021 (-3400 6675);
PAINT PURPLE (-3400 6675);
DISPLAY INVISIBLE (-3400 6675);
FORCEPROP 2 LAST CDS_LIB standard
J 0
(-3125 6625);
DISPLAY INVISIBLE (-3125 6625);
FORCEPROP 1 LAST OFFPAGE TRUE
J 0
(-2800 6500);
DISPLAY 1.042553 (-2800 6500);
PAINT GREEN (-2800 6500);
DISPLAY INVISIBLE (-2800 6500);
FORCEPROP 1 LAST COMMENT_BODY TRUE
J 0
(-3000 6525);
DISPLAY 1.042553 (-3000 6525);
PAINT GREEN (-3000 6525);
DISPLAY INVISIBLE (-3000 6525);
FORCEPROP 2 LAST PATH I39
J 0
(-3375 6675);
DISPLAY 0.680851 (-3375 6675);
DISPLAY INVISIBLE (-3375 6675);
FORCEADD Q_RES..1
(-6300 4950);
FORCEPROP 1 LAST LOCATION R333
J 0
(-6550 4950);
DISPLAY 0.638298 (-6550 4950);
FORCEPROP 2 LAST $SEC 1
J 0
(-6350 5150);
DISPLAY 0.680851 (-6350 5150);
PAINT MONO (-6350 5150);
DISPLAY INVISIBLE (-6350 5150);
FORCEPROP 2 LAST CDS_SEC 1
J 0
(-6350 5150);
DISPLAY 1.021277 (-6350 5150);
DISPLAY INVISIBLE (-6350 5150);
FORCEPROP 1 LASTPIN (-6400 4950) $PN 1
J 0
(-6388 4962);
DISPLAY 0.787234 (-6388 4962);
FORCEPROP 1 LASTPIN (-6200 4950) $PN 2
J 0
(-6238 4962);
DISPLAY 0.787234 (-6238 4962);
FORCEPROP 1 LAST VALUE 0
J 2
(-6150 4950);
DISPLAY 0.617021 (-6150 4950);
FORCEPROP 1 LAST TOLERANCE 5%
J 0
(-6125 4950);
DISPLAY 0.617021 (-6125 4950);
FORCEPROP 1 LAST MATERIAL CHIP
J 0
(-6050 4950);
DISPLAY 0.617021 (-6050 4950);
FORCEPROP 1 LAST PACK_TYPE 0402LF
J 0
(-6450 5050);
DISPLAY 0.617021 (-6450 5050);
FORCEPROP 1 LAST WATTAGE 1/16W
J 2
(-6100 5050);
DISPLAY 0.617021 (-6100 5050);
FORCEPROP 1 LAST PART_NUMBER CS00002JB13
J 0
(-6450 5000);
DISPLAY 0.617021 (-6450 5000);
DISPLAY INVISIBLE (-6450 5000);
FORCEPROP 2 LAST CDS_LIB pure_quanta
J 0
(-6300 4950);
PAINT MONO (-6300 4950);
DISPLAY INVISIBLE (-6300 4950);
FORCEPROP 2 LAST BOM_COST VR_SYSTEM 
J 0
(-6350 5100);
DISPLAY 0.680851 (-6350 5100);
DISPLAY INVISIBLE (-6350 5100);
FORCEPROP 1 LAST PATH I4
J 0
(-6350 5100);
DISPLAY 0.978723 (-6350 5100);
PAINT WHITE (-6350 5100);
DISPLAY INVISIBLE (-6350 5100);
FORCEADD UNIVERSAL_GND..1
(-3375 7100);
FORCEPROP 3 LASTPIN (-3375 7150) SIG_NAME GND\g
J 0
(-3365 7160);
DISPLAY 0.659574 (-3365 7160);
PAINT MONO (-3365 7160);
DISPLAY INVISIBLE (-3365 7160);
FORCEPROP 2 LAST BOM_COST VR_SYSTEM 
J 0
(-3675 7175);
DISPLAY 0.680851 (-3675 7175);
DISPLAY INVISIBLE (-3675 7175);
FORCEPROP 2 LAST CDS_LIB pure_quanta_power
J 0
(-3375 7100);
DISPLAY INVISIBLE (-3375 7100);
FORCEPROP 0 LAST VOLTAGE 0
J 0
(-3375 7100);
PAINT SKYBLUE (-3375 7100);
DISPLAY INVISIBLE (-3375 7100);
FORCEPROP 1 LAST HDL_POWER GND
J 1
(-3350 7025);
DISPLAY 0.872340 (-3350 7025);
PAINT GREEN (-3350 7025);
DISPLAY INVISIBLE (-3350 7025);
FORCEPROP 1 LAST PATH I40
J 0
(-3300 7100);
DISPLAY 0.872340 (-3300 7100);
PAINT AQUA (-3300 7100);
DISPLAY INVISIBLE (-3300 7100);
FORCEADD Q_CAP..1
(-3375 7425);
FORCEPROP 1 LAST LOCATION C1227
J 0
(-3325 7525);
DISPLAY 0.978723 (-3325 7525);
FORCEPROP 2 LAST $SEC 1
J 0
(-3325 7625);
DISPLAY 0.680851 (-3325 7625);
PAINT MONO (-3325 7625);
DISPLAY INVISIBLE (-3325 7625);
FORCEPROP 2 LAST CDS_SEC 1
J 0
(-3325 7625);
DISPLAY 1.021277 (-3325 7625);
DISPLAY INVISIBLE (-3325 7625);
FORCEPROP 1 LASTPIN (-3375 7525) $PN 1
J 0
(-3365 7505);
DISPLAY 0.787234 (-3365 7505);
FORCEPROP 1 LASTPIN (-3375 7325) $PN 2
J 0
(-3365 7305);
DISPLAY 0.787234 (-3365 7305);
FORCEPROP 1 LAST MATERIAL X7R
J 0
(-3325 7325);
DISPLAY 0.489362 (-3325 7325);
FORCEPROP 1 LAST PACK_TYPE C0402
J 0
(-3325 7225);
DISPLAY 0.489362 (-3325 7225);
FORCEPROP 1 LAST VALUE 100NF
J 0
(-3325 7475);
DISPLAY 0.489362 (-3325 7475);
FORCEPROP 1 LAST VOLTAGE 50V
J 0
(-3325 7425);
DISPLAY 0.489362 (-3325 7425);
FORCEPROP 1 LAST TOLERANCE 10%
J 0
(-3325 7375);
DISPLAY 0.489362 (-3325 7375);
FORCEPROP 1 LAST PART_NUMBER CH4106K1B01
J 0
(-3325 7275);
DISPLAY 0.489362 (-3325 7275);
DISPLAY INVISIBLE (-3325 7275);
FORCEPROP 2 LAST CDS_LIB pure_quanta
J 0
(-3375 7425);
PAINT MONO (-3375 7425);
DISPLAY INVISIBLE (-3375 7425);
FORCEPROP 2 LAST BOM_COST VR_SYSTEM 
J 0
(-3325 7575);
DISPLAY 0.680851 (-3325 7575);
DISPLAY INVISIBLE (-3325 7575);
FORCEPROP 2 LAST REUSE_ID 81
J 0
(-3325 7625);
DISPLAY 0.680851 (-3325 7625);
DISPLAY INVISIBLE (-3325 7625);
FORCEPROP 1 LAST PATH I41
J 0
(-3325 7575);
DISPLAY 0.978723 (-3325 7575);
PAINT WHITE (-3325 7575);
DISPLAY INVISIBLE (-3325 7575);
FORCEADD UNIVERSAL_POWER..1
(-3475 7900);
FORCEPROP 3 LASTPIN (-3475 7850) SIG_NAME P5V\g
J 0
(-3465 7860);
DISPLAY 0.659574 (-3465 7860);
PAINT MONO (-3465 7860);
DISPLAY INVISIBLE (-3465 7860);
FORCEPROP 1 LAST HDL_POWER P5V
J 1
(-3475 7950);
DISPLAY 0.617021 (-3475 7950);
PAINT GREEN (-3475 7950);
FORCEPROP 2 LAST BOM_COST VR_SYSTEM 
J 0
(-3475 8000);
DISPLAY 0.680851 (-3475 8000);
DISPLAY INVISIBLE (-3475 8000);
FORCEPROP 2 LAST CDS_LIB pure_quanta_power
J 0
(-3475 7900);
PAINT RED (-3475 7900);
DISPLAY INVISIBLE (-3475 7900);
FORCEPROP 1 LAST PATH I42
J 0
(-3425 7925);
DISPLAY 0.872340 (-3425 7925);
PAINT AQUA (-3425 7925);
DISPLAY INVISIBLE (-3425 7925);
FORCEADD Q_CAP..1
(-3050 7425);
FORCEPROP 1 LAST LOCATION C1331
J 0
(-3000 7525);
DISPLAY 0.978723 (-3000 7525);
FORCEPROP 2 LAST $SEC 1
J 0
(-3000 7625);
DISPLAY 0.680851 (-3000 7625);
PAINT MONO (-3000 7625);
DISPLAY INVISIBLE (-3000 7625);
FORCEPROP 2 LAST CDS_SEC 1
J 0
(-3000 7625);
DISPLAY 1.021277 (-3000 7625);
DISPLAY INVISIBLE (-3000 7625);
FORCEPROP 1 LASTPIN (-3050 7525) $PN 1
J 0
(-3040 7505);
DISPLAY 0.787234 (-3040 7505);
FORCEPROP 1 LASTPIN (-3050 7325) $PN 2
J 0
(-3040 7305);
DISPLAY 0.787234 (-3040 7305);
FORCEPROP 1 LAST VALUE 10UF
J 0
(-3000 7475);
DISPLAY 0.489362 (-3000 7475);
FORCEPROP 1 LAST VOLTAGE 16V
J 0
(-3000 7425);
DISPLAY 0.489362 (-3000 7425);
FORCEPROP 1 LAST TOLERANCE 10%
J 0
(-3000 7375);
DISPLAY 0.489362 (-3000 7375);
FORCEPROP 1 LAST MATERIAL X6S
J 0
(-3000 7325);
DISPLAY 0.489362 (-3000 7325);
FORCEPROP 1 LAST PACK_TYPE C0805
J 0
(-3000 7225);
DISPLAY 0.489362 (-3000 7225);
FORCEPROP 1 LAST PART_NUMBER CH6103KEA00
J 0
(-3000 7275);
DISPLAY 0.489362 (-3000 7275);
DISPLAY INVISIBLE (-3000 7275);
FORCEPROP 2 LAST CDS_LIB pure_quanta
J 0
(-3050 7425);
PAINT MONO (-3050 7425);
DISPLAY INVISIBLE (-3050 7425);
FORCEPROP 2 LAST REUSE_ID 6
J 0
(-3000 7625);
DISPLAY 0.680851 (-3000 7625);
DISPLAY INVISIBLE (-3000 7625);
FORCEPROP 2 LAST BOM_COST VR_SYSTEM 
J 0
(-3000 7575);
DISPLAY 0.680851 (-3000 7575);
DISPLAY INVISIBLE (-3000 7575);
FORCEPROP 1 LAST PATH I43
J 0
(-3000 7575);
DISPLAY 0.978723 (-3000 7575);
PAINT WHITE (-3000 7575);
DISPLAY INVISIBLE (-3000 7575);
FORCEADD UNIVERSAL_GND..1
(-2350 6250);
FORCEPROP 3 LASTPIN (-2350 6300) SIG_NAME GND\g
J 0
(-2340 6310);
DISPLAY 0.659574 (-2340 6310);
PAINT MONO (-2340 6310);
DISPLAY INVISIBLE (-2340 6310);
FORCEPROP 2 LAST BOM_COST VR_SYSTEM 
J 0
(-2650 6325);
DISPLAY 0.680851 (-2650 6325);
DISPLAY INVISIBLE (-2650 6325);
FORCEPROP 0 LAST VOLTAGE 0
J 0
(-2350 6250);
PAINT SKYBLUE (-2350 6250);
DISPLAY INVISIBLE (-2350 6250);
FORCEPROP 2 LAST CDS_LIB pure_quanta_power
J 0
(-2350 6250);
DISPLAY INVISIBLE (-2350 6250);
FORCEPROP 1 LAST HDL_POWER GND
J 1
(-2325 6175);
DISPLAY 0.872340 (-2325 6175);
PAINT GREEN (-2325 6175);
DISPLAY INVISIBLE (-2325 6175);
FORCEPROP 1 LAST PATH I44
J 0
(-2275 6250);
DISPLAY 0.872340 (-2275 6250);
PAINT AQUA (-2275 6250);
DISPLAY INVISIBLE (-2275 6250);
FORCEADD Q_RES..2
(-2350 7275);
FORCEPROP 1 LAST LOCATION R4638
J 0
(-2305 7400);
DISPLAY 0.978723 (-2305 7400);
FORCEPROP 0 LAST $SEC 1
J 0
(-2300 7450);
DISPLAY 0.680851 (-2300 7450);
PAINT MONO (-2300 7450);
DISPLAY INVISIBLE (-2300 7450);
FORCEPROP 0 LAST CDS_SEC 1
J 0
(-2300 7450);
DISPLAY 1.021277 (-2300 7450);
DISPLAY INVISIBLE (-2300 7450);
FORCEPROP 1 LASTPIN (-2350 7375) $PN 1
J 0
(-2345 7337);
DISPLAY 0.787234 (-2345 7337);
PAINT MONO (-2345 7337);
FORCEPROP 1 LASTPIN (-2350 7175) $PN 2
J 0
(-2345 7185);
DISPLAY 0.787234 (-2345 7185);
PAINT MONO (-2345 7185);
FORCEPROP 1 LAST TOLERANCE 1%
J 0
(-2305 7300);
DISPLAY 0.978723 (-2305 7300);
FORCEPROP 1 LAST WATTAGE 1/4W
J 0
(-2310 7250);
DISPLAY 0.978723 (-2310 7250);
FORCEPROP 1 LAST MATERIAL CHIP
J 0
(-2310 7200);
DISPLAY 0.978723 (-2310 7200);
FORCEPROP 1 LAST VALUE 243
J 0
(-2305 7350);
DISPLAY 0.978723 (-2305 7350);
FORCEPROP 1 LAST PACK_TYPE 1206LF
J 0
(-2310 7100);
DISPLAY 0.978723 (-2310 7100);
FORCEPROP 1 LAST PART_NUMBER CS12436F201
J 0
(-2310 7150);
DISPLAY 0.978723 (-2310 7150);
DISPLAY INVISIBLE (-2310 7150);
FORCEPROP 2 LAST CDS_LIB pure_quanta
J 0
(-2350 7275);
DISPLAY INVISIBLE (-2350 7275);
FORCEPROP 1 LAST PATH I45
J 0
(-2300 7450);
DISPLAY 0.978723 (-2300 7450);
PAINT WHITE (-2300 7450);
DISPLAY INVISIBLE (-2300 7450);
FORCEADD UNIVERSAL_GND..1
(-1225 5375);
FORCEPROP 3 LASTPIN (-1225 5425) SIG_NAME GND\g
J 0
(-1215 5435);
DISPLAY 0.659574 (-1215 5435);
PAINT MONO (-1215 5435);
DISPLAY INVISIBLE (-1215 5435);
FORCEPROP 0 LAST VOLTAGE 0
J 0
(-1225 5375);
PAINT SKYBLUE (-1225 5375);
DISPLAY INVISIBLE (-1225 5375);
FORCEPROP 2 LAST CDS_LIB pure_quanta_power
J 0
(-1225 5375);
DISPLAY INVISIBLE (-1225 5375);
FORCEPROP 2 LAST BOM_COST VR_SYSTEM 
J 0
(-1525 5450);
DISPLAY 0.680851 (-1525 5450);
DISPLAY INVISIBLE (-1525 5450);
FORCEPROP 1 LAST HDL_POWER GND
J 1
(-1200 5300);
DISPLAY 0.872340 (-1200 5300);
PAINT GREEN (-1200 5300);
DISPLAY INVISIBLE (-1200 5300);
FORCEPROP 1 LAST PATH I46
J 0
(-1150 5375);
DISPLAY 0.872340 (-1150 5375);
PAINT AQUA (-1150 5375);
DISPLAY INVISIBLE (-1150 5375);
FORCEADD Q_CAP..1
R 2
(-1225 5700);
FORCEPROP 1 LAST LOCATION C1332
J 2
(-1275 5800);
DISPLAY 0.978723 (-1275 5800);
FORCEPROP 2 LAST $SEC 1
J 0
(-1275 5900);
DISPLAY 0.680851 (-1275 5900);
PAINT MONO (-1275 5900);
DISPLAY INVISIBLE (-1275 5900);
FORCEPROP 2 LAST CDS_SEC 1
J 0
(-1275 5900);
DISPLAY 1.021277 (-1275 5900);
DISPLAY INVISIBLE (-1275 5900);
FORCEPROP 1 LASTPIN (-1225 5800) $PN 1
J 2
(-1235 5780);
DISPLAY 0.787234 (-1235 5780);
FORCEPROP 1 LASTPIN (-1225 5600) $PN 2
J 2
(-1235 5580);
DISPLAY 0.787234 (-1235 5580);
FORCEPROP 1 LAST PACK_TYPE C0402
J 2
(-1275 5500);
DISPLAY 0.489362 (-1275 5500);
FORCEPROP 1 LAST VALUE 100NF
J 2
(-1275 5750);
DISPLAY 0.489362 (-1275 5750);
FORCEPROP 1 LAST TOLERANCE 10%
J 2
(-1275 5650);
DISPLAY 0.489362 (-1275 5650);
FORCEPROP 1 LAST VOLTAGE 50V
J 2
(-1275 5700);
DISPLAY 0.489362 (-1275 5700);
FORCEPROP 1 LAST MATERIAL X7R
J 2
(-1275 5600);
DISPLAY 0.489362 (-1275 5600);
FORCEPROP 1 LAST PART_NUMBER CH4106K1B01
J 2
(-1275 5550);
DISPLAY 0.489362 (-1275 5550);
DISPLAY INVISIBLE (-1275 5550);
FORCEPROP 2 LAST BOM_COST VR_SYSTEM 
J 0
(-1275 5850);
DISPLAY 0.680851 (-1275 5850);
DISPLAY INVISIBLE (-1275 5850);
FORCEPROP 2 LAST CDS_LIB pure_quanta
J 0
(-1225 5700);
PAINT MONO (-1225 5700);
DISPLAY INVISIBLE (-1225 5700);
FORCEPROP 1 LAST PATH I48
J 2
(-1275 5850);
DISPLAY 0.978723 (-1275 5850);
PAINT WHITE (-1275 5850);
DISPLAY INVISIBLE (-1275 5850);
FORCEADD Q_CAP..1
R 2
(-900 5700);
FORCEPROP 1 LAST LOCATION C1333
J 2
(-950 5800);
DISPLAY 0.978723 (-950 5800);
FORCEPROP 2 LAST $SEC 1
J 0
(-950 5900);
DISPLAY 0.680851 (-950 5900);
PAINT MONO (-950 5900);
DISPLAY INVISIBLE (-950 5900);
FORCEPROP 2 LAST CDS_SEC 1
J 0
(-950 5900);
DISPLAY 1.021277 (-950 5900);
DISPLAY INVISIBLE (-950 5900);
FORCEPROP 1 LASTPIN (-900 5800) $PN 1
J 2
(-910 5780);
DISPLAY 0.787234 (-910 5780);
FORCEPROP 1 LASTPIN (-900 5600) $PN 2
J 2
(-910 5580);
DISPLAY 0.787234 (-910 5580);
FORCEPROP 1 LAST VOLTAGE 16V
J 2
(-950 5700);
DISPLAY 0.489362 (-950 5700);
FORCEPROP 1 LAST TOLERANCE 10%
J 2
(-950 5650);
DISPLAY 0.489362 (-950 5650);
FORCEPROP 1 LAST PACK_TYPE C0805
J 2
(-950 5500);
DISPLAY 0.489362 (-950 5500);
FORCEPROP 1 LAST VALUE 10UF
J 2
(-950 5750);
DISPLAY 0.489362 (-950 5750);
FORCEPROP 1 LAST MATERIAL X6S
J 2
(-950 5600);
DISPLAY 0.489362 (-950 5600);
FORCEPROP 1 LAST PART_NUMBER CH6103KEA00
J 2
(-950 5550);
DISPLAY 0.489362 (-950 5550);
DISPLAY INVISIBLE (-950 5550);
FORCEPROP 2 LAST BOM_COST VR_SYSTEM 
J 0
(-950 5850);
DISPLAY 0.680851 (-950 5850);
DISPLAY INVISIBLE (-950 5850);
FORCEPROP 2 LAST CDS_LIB pure_quanta
J 0
(-900 5700);
PAINT MONO (-900 5700);
DISPLAY INVISIBLE (-900 5700);
FORCEPROP 1 LAST PATH I49
J 2
(-950 5850);
DISPLAY 0.978723 (-950 5850);
PAINT WHITE (-950 5850);
DISPLAY INVISIBLE (-950 5850);
FORCEADD MOSFET_NCH_1D3S..1
R 7
(75 5250);
FORCEPROP 1 LAST LOCATION Q56
J 0
(-93 5427);
DISPLAY 0.723404 (-93 5427);
PAINT GREEN (-93 5427);
FORCEPROP 2 LAST $SEC 1
J 0
(-125 5725);
DISPLAY 0.680851 (-125 5725);
PAINT MONO (-125 5725);
DISPLAY INVISIBLE (-125 5725);
FORCEPROP 2 LAST CDS_SEC 1
J 0
(-125 5725);
DISPLAY 1.021277 (-125 5725);
DISPLAY INVISIBLE (-125 5725);
FORCEPROP 2 LASTPIN (325 5350) $PN 1
J 0
(335 5360);
DISPLAY 0.808511 (335 5360);
FORCEPROP 2 LASTPIN (325 5250) $PN 2
J 0
(335 5260);
DISPLAY 0.808511 (335 5260);
FORCEPROP 2 LASTPIN (325 5150) $PN 3
J 0
(335 5160);
DISPLAY 0.808511 (335 5160);
FORCEPROP 2 LASTPIN (125 5050) $PN 4
R 1
J 2
(115 5040);
DISPLAY 0.808511 (115 5040);
FORCEPROP 2 LASTPIN (-175 5250) $PN 5
J 2
(-185 5260);
DISPLAY 0.808511 (-185 5260);
FORCEPROP 2 LAST VALUE PSMNR58-30YLH
J 0
(-125 5600);
DISPLAY 0.808511 (-125 5600);
FORCEPROP 2 LAST PART_TYPE SMLF
J 0
(-125 5675);
DISPLAY 0.808511 (-125 5675);
FORCEPROP 1 LAST MATERIAL IC
J 0
(-109 5477);
DISPLAY 0.723404 (-109 5477);
PAINT GREEN (-109 5477);
FORCEPROP 1 LAST PART_NUMBER BAMNR580000
J 0
(-125 5527);
DISPLAY 0.723404 (-125 5527);
PAINT GREEN (-125 5527);
DISPLAY INVISIBLE (-125 5527);
FORCEPROP 1 LAST NEEDS_NO_SIZE TRUE
R 1
J 0
(74 5250);
DISPLAY 0.468085 (74 5250);
PAINT GREEN (74 5250);
DISPLAY INVISIBLE (74 5250);
FORCEPROP 1 LAST CDS_LMAN_SYM_OUTLINE -150,200,150,-200
R 1
J 0
(75 5250);
DISPLAY 0.468085 (75 5250);
PAINT GREEN (75 5250);
DISPLAY INVISIBLE (75 5250);
FORCEPROP 2 LAST CDS_LIB pure_quanta
J 0
(75 5250);
PAINT MONO (75 5250);
DISPLAY INVISIBLE (75 5250);
FORCEPROP 1 LAST PATH I50
R 1
J 0
(75 5250);
DISPLAY 0.723404 (75 5250);
PAINT GREEN (75 5250);
DISPLAY INVISIBLE (75 5250);
FORCEADD Q_CAP..1
R 2
(-500 5700);
FORCEPROP 1 LAST LOCATION C60
J 2
(-550 5800);
DISPLAY 0.978723 (-550 5800);
FORCEPROP 2 LAST $SEC 1
J 0
(-550 5900);
DISPLAY 0.680851 (-550 5900);
PAINT MONO (-550 5900);
DISPLAY INVISIBLE (-550 5900);
FORCEPROP 2 LAST CDS_SEC 1
J 0
(-550 5900);
DISPLAY 1.021277 (-550 5900);
DISPLAY INVISIBLE (-550 5900);
FORCEPROP 1 LASTPIN (-500 5800) $PN 1
J 2
(-510 5780);
DISPLAY 0.787234 (-510 5780);
FORCEPROP 1 LASTPIN (-500 5600) $PN 2
J 2
(-510 5580);
DISPLAY 0.787234 (-510 5580);
FORCEPROP 1 LAST MATERIAL EMPTY
J 2
(-550 5600);
DISPLAY 0.489362 (-550 5600);
PAINT RED (-550 5600);
FORCEPROP 1 LAST TOLERANCE 10%
J 2
(-550 5650);
DISPLAY 0.489362 (-550 5650);
FORCEPROP 1 LAST PACK_TYPE C0805
J 2
(-550 5500);
DISPLAY 0.489362 (-550 5500);
FORCEPROP 1 LAST VALUE 10UF
J 2
(-550 5750);
DISPLAY 0.489362 (-550 5750);
FORCEPROP 1 LAST VOLTAGE 16V
J 2
(-550 5700);
DISPLAY 0.489362 (-550 5700);
FORCEPROP 1 LAST PART_NUMBER CH6103KEA00
J 2
(-550 5550);
DISPLAY 0.489362 (-550 5550);
DISPLAY INVISIBLE (-550 5550);
FORCEPROP 2 LAST BOM_COST VR_SYSTEM 
J 0
(-550 5850);
DISPLAY 0.680851 (-550 5850);
DISPLAY INVISIBLE (-550 5850);
FORCEPROP 2 LAST CDS_LIB pure_quanta
J 0
(-500 5700);
PAINT MONO (-500 5700);
DISPLAY INVISIBLE (-500 5700);
FORCEPROP 1 LAST PATH I51
J 2
(-550 5850);
DISPLAY 0.978723 (-550 5850);
PAINT WHITE (-550 5850);
DISPLAY INVISIBLE (-550 5850);
FORCEADD P1V0_AUX..1
(-326 6099);
FORCEPROP 3 LASTPIN (-326 6049) SIG_NAME P3V3_AUX\g
J 0
(-316 6059);
DISPLAY 0.659574 (-316 6059);
PAINT MONO (-316 6059);
DISPLAY INVISIBLE (-316 6059);
FORCEPROP 1 LAST HDL_POWER P3V3_AUX
J 1
(-316 6139);
DISPLAY 0.617021 (-316 6139);
PAINT GREEN (-316 6139);
FORCEPROP 2 LAST BOM_COST VR_SYSTEM 
J 0
(-300 6175);
DISPLAY 0.680851 (-300 6175);
DISPLAY INVISIBLE (-300 6175);
FORCEPROP 2 LAST CDS_LIB pure_quanta_power
J 0
(-326 6099);
PAINT RED (-326 6099);
DISPLAY INVISIBLE (-326 6099);
FORCEPROP 1 LAST PATH I52
J 0
(-276 6124);
DISPLAY 0.872340 (-276 6124);
PAINT AQUA (-276 6124);
DISPLAY INVISIBLE (-276 6124);
FORCEADD UNIVERSAL_GND..1
(1100 5350);
FORCEPROP 3 LASTPIN (1100 5400) SIG_NAME GND\g
J 0
(1110 5410);
DISPLAY 0.659574 (1110 5410);
PAINT MONO (1110 5410);
DISPLAY INVISIBLE (1110 5410);
FORCEPROP 2 LAST BOM_COST VR_SYSTEM 
J 0
(800 5425);
DISPLAY 0.680851 (800 5425);
DISPLAY INVISIBLE (800 5425);
FORCEPROP 2 LAST CDS_LIB pure_quanta_power
J 0
(1100 5350);
DISPLAY INVISIBLE (1100 5350);
FORCEPROP 0 LAST VOLTAGE 0
J 0
(1100 5350);
PAINT SKYBLUE (1100 5350);
DISPLAY INVISIBLE (1100 5350);
FORCEPROP 1 LAST HDL_POWER GND
J 1
(1125 5275);
DISPLAY 0.872340 (1125 5275);
PAINT GREEN (1125 5275);
DISPLAY INVISIBLE (1125 5275);
FORCEPROP 1 LAST PATH I58
J 0
(1175 5350);
DISPLAY 0.872340 (1175 5350);
PAINT AQUA (1175 5350);
DISPLAY INVISIBLE (1175 5350);
FORCEADD Q_CAP..1
(725 5700);
FORCEPROP 1 LAST LOCATION C61
J 0
(775 5800);
DISPLAY 0.978723 (775 5800);
FORCEPROP 2 LAST $SEC 1
J 0
(775 5900);
DISPLAY 0.680851 (775 5900);
PAINT MONO (775 5900);
DISPLAY INVISIBLE (775 5900);
FORCEPROP 2 LAST CDS_SEC 1
J 0
(775 5900);
DISPLAY 1.021277 (775 5900);
DISPLAY INVISIBLE (775 5900);
FORCEPROP 1 LASTPIN (725 5800) $PN 1
J 0
(735 5780);
DISPLAY 0.787234 (735 5780);
FORCEPROP 1 LASTPIN (725 5600) $PN 2
J 0
(735 5580);
DISPLAY 0.787234 (735 5580);
FORCEPROP 1 LAST PACK_TYPE C0402
J 0
(775 5500);
DISPLAY 0.489362 (775 5500);
FORCEPROP 1 LAST VOLTAGE 50V
J 0
(775 5700);
DISPLAY 0.489362 (775 5700);
FORCEPROP 1 LAST TOLERANCE 10%
J 0
(775 5650);
DISPLAY 0.489362 (775 5650);
FORCEPROP 1 LAST MATERIAL X7R
J 0
(775 5600);
DISPLAY 0.489362 (775 5600);
FORCEPROP 1 LAST VALUE 100NF
J 0
(775 5750);
DISPLAY 0.489362 (775 5750);
FORCEPROP 1 LAST PART_NUMBER CH4106K1B01
J 0
(775 5550);
DISPLAY 0.489362 (775 5550);
DISPLAY INVISIBLE (775 5550);
FORCEPROP 2 LAST BOM_COST VR_SYSTEM 
J 0
(775 5850);
DISPLAY 0.680851 (775 5850);
DISPLAY INVISIBLE (775 5850);
FORCEPROP 2 LAST CDS_LIB pure_quanta
J 0
(725 5700);
PAINT MONO (725 5700);
DISPLAY INVISIBLE (725 5700);
FORCEPROP 1 LAST PATH I59
J 0
(775 5850);
DISPLAY 0.978723 (775 5850);
PAINT WHITE (775 5850);
DISPLAY INVISIBLE (775 5850);
FORCEADD UNIVERSAL_GND..1
(-5775 4300);
FORCEPROP 3 LASTPIN (-5775 4350) SIG_NAME GND\g
J 0
(-5765 4360);
DISPLAY 0.659574 (-5765 4360);
PAINT MONO (-5765 4360);
DISPLAY INVISIBLE (-5765 4360);
FORCEPROP 2 LAST BOM_COST VR_SYSTEM 
J 0
(-6075 4375);
DISPLAY 0.680851 (-6075 4375);
DISPLAY INVISIBLE (-6075 4375);
FORCEPROP 0 LAST VOLTAGE 0
J 0
(-5775 4300);
PAINT SKYBLUE (-5775 4300);
DISPLAY INVISIBLE (-5775 4300);
FORCEPROP 2 LAST CDS_LIB pure_quanta_power
J 0
(-5775 4300);
PAINT MONO (-5775 4300);
DISPLAY INVISIBLE (-5775 4300);
FORCEPROP 1 LAST HDL_POWER GND
J 1
(-5750 4225);
DISPLAY 0.872340 (-5750 4225);
PAINT GREEN (-5750 4225);
DISPLAY INVISIBLE (-5750 4225);
FORCEPROP 1 LAST PATH I6
J 0
(-5700 4300);
DISPLAY 0.872340 (-5700 4300);
PAINT AQUA (-5700 4300);
DISPLAY INVISIBLE (-5700 4300);
FORCEADD UNIVERSAL_POWER..1
(625 6100);
FORCEPROP 3 LASTPIN (625 6050) SIG_NAME P3V3\g
J 0
(635 6060);
DISPLAY 0.659574 (635 6060);
PAINT MONO (635 6060);
DISPLAY INVISIBLE (635 6060);
FORCEPROP 1 LAST HDL_POWER P3V3
J 1
(625 6150);
DISPLAY 0.617021 (625 6150);
PAINT GREEN (625 6150);
FORCEPROP 2 LAST BOM_COST VR_SYSTEM 
J 0
(625 6200);
DISPLAY 0.680851 (625 6200);
DISPLAY INVISIBLE (625 6200);
FORCEPROP 2 LAST CDS_LIB pure_quanta_power
J 0
(625 6100);
PAINT RED (625 6100);
DISPLAY INVISIBLE (625 6100);
FORCEPROP 1 LAST PATH I60
J 0
(675 6125);
DISPLAY 0.872340 (675 6125);
PAINT AQUA (675 6125);
DISPLAY INVISIBLE (675 6125);
FORCEADD Q_CAP..1
(1100 5700);
FORCEPROP 1 LAST LOCATION C1340
J 0
(1150 5800);
DISPLAY 0.978723 (1150 5800);
FORCEPROP 2 LAST $SEC 1
J 0
(1150 5900);
DISPLAY 0.680851 (1150 5900);
PAINT MONO (1150 5900);
DISPLAY INVISIBLE (1150 5900);
FORCEPROP 2 LAST CDS_SEC 1
J 0
(1150 5900);
DISPLAY 1.021277 (1150 5900);
DISPLAY INVISIBLE (1150 5900);
FORCEPROP 1 LASTPIN (1100 5800) $PN 1
J 0
(1110 5780);
DISPLAY 0.787234 (1110 5780);
FORCEPROP 1 LASTPIN (1100 5600) $PN 2
J 0
(1110 5580);
DISPLAY 0.787234 (1110 5580);
FORCEPROP 1 LAST PACK_TYPE C0805
J 0
(1150 5500);
DISPLAY 0.489362 (1150 5500);
FORCEPROP 1 LAST TOLERANCE 10%
J 0
(1150 5650);
DISPLAY 0.489362 (1150 5650);
FORCEPROP 1 LAST MATERIAL X6S
J 0
(1150 5600);
DISPLAY 0.489362 (1150 5600);
FORCEPROP 1 LAST VOLTAGE 16V
J 0
(1150 5700);
DISPLAY 0.489362 (1150 5700);
FORCEPROP 1 LAST VALUE 10UF
J 0
(1150 5750);
DISPLAY 0.489362 (1150 5750);
FORCEPROP 1 LAST PART_NUMBER CH6103KEA00
J 0
(1150 5550);
DISPLAY 0.489362 (1150 5550);
DISPLAY INVISIBLE (1150 5550);
FORCEPROP 2 LAST BOM_COST VR_SYSTEM 
J 0
(1150 5850);
DISPLAY 0.680851 (1150 5850);
DISPLAY INVISIBLE (1150 5850);
FORCEPROP 2 LAST CDS_LIB pure_quanta
J 0
(1100 5700);
PAINT MONO (1100 5700);
DISPLAY INVISIBLE (1100 5700);
FORCEPROP 1 LAST PATH I61
J 0
(1150 5850);
DISPLAY 0.978723 (1150 5850);
PAINT WHITE (1150 5850);
DISPLAY INVISIBLE (1150 5850);
FORCEADD MOSFET_NCH_GDS_ESD_PROTECTED..1
(-2375 6625);
FORCEPROP 1 LAST LOCATION U324
J 0
(-2233 6589);
DISPLAY 0.723404 (-2233 6589);
PAINT GREEN (-2233 6589);
FORCEPROP 0 LAST $SEC 1
J 0
(-2225 6775);
DISPLAY 0.680851 (-2225 6775);
PAINT MONO (-2225 6775);
DISPLAY INVISIBLE (-2225 6775);
FORCEPROP 0 LAST CDS_SEC 1
J 0
(-2225 6775);
DISPLAY 1.021277 (-2225 6775);
DISPLAY INVISIBLE (-2225 6775);
FORCEPROP 0 LASTPIN (-2350 6825) $PN D
R 1
J 0
(-2360 6835);
DISPLAY 0.680851 (-2360 6835);
PAINT MONO (-2360 6835);
FORCEPROP 0 LASTPIN (-2550 6625) $PN G
J 2
(-2560 6635);
DISPLAY 0.680851 (-2560 6635);
PAINT MONO (-2560 6635);
FORCEPROP 0 LASTPIN (-2350 6425) $PN S
R 1
J 2
(-2360 6415);
DISPLAY 0.680851 (-2360 6415);
PAINT MONO (-2360 6415);
FORCEPROP 1 LAST MATERIAL IC
J 0
(-2233 6480);
DISPLAY 0.723404 (-2233 6480);
PAINT GREEN (-2233 6480);
FORCEPROP 2 LAST VALUE 2N7002K
J 0
(-2225 6675);
DISPLAY 0.680851 (-2225 6675);
FORCEPROP 2 LAST PART_TYPE SMLF
J 0
(-2225 6725);
DISPLAY 0.680851 (-2225 6725);
FORCEPROP 1 LAST PART_NUMBER BAM70020002
J 0
(-2233 6537);
DISPLAY 0.723404 (-2233 6537);
PAINT GREEN (-2233 6537);
DISPLAY INVISIBLE (-2233 6537);
FORCEPROP 2 LAST CDS_LIB pure_quanta
J 0
(-2375 6625);
DISPLAY INVISIBLE (-2375 6625);
FORCEPROP 1 LAST CDS_LMAN_SYM_OUTLINE -125,150,125,-150
J 0
(-2375 6625);
DISPLAY 0.468085 (-2375 6625);
PAINT GREEN (-2375 6625);
DISPLAY INVISIBLE (-2375 6625);
FORCEPROP 1 LAST NEEDS_NO_SIZE TRUE
J 0
(-2250 6515);
DISPLAY 0.723404 (-2250 6515);
PAINT GREEN (-2250 6515);
DISPLAY INVISIBLE (-2250 6515);
FORCEPROP 1 LAST PATH I62
J 0
(-2250 6475);
DISPLAY 0.723404 (-2250 6475);
PAINT GREEN (-2250 6475);
DISPLAY INVISIBLE (-2250 6475);
FORCEADD Q_RES..2
(-5775 4675);
FORCEPROP 1 LAST LOCATION R334
J 0
(-5730 4800);
DISPLAY 0.638298 (-5730 4800);
FORCEPROP 0 LAST $SEC 1
J 0
(-5725 4850);
DISPLAY 0.680851 (-5725 4850);
PAINT MONO (-5725 4850);
DISPLAY INVISIBLE (-5725 4850);
FORCEPROP 2 LAST CDS_SEC 1
J 0
(-5725 4900);
DISPLAY 1.021277 (-5725 4900);
DISPLAY INVISIBLE (-5725 4900);
FORCEPROP 1 LASTPIN (-5775 4775) $PN 1
J 0
(-5770 4737);
DISPLAY 0.787234 (-5770 4737);
PAINT MONO (-5770 4737);
FORCEPROP 1 LASTPIN (-5775 4575) $PN 2
J 0
(-5770 4585);
DISPLAY 0.787234 (-5770 4585);
PAINT MONO (-5770 4585);
FORCEPROP 1 LAST MATERIAL CHIP
J 0
(-5735 4600);
DISPLAY 0.638298 (-5735 4600);
FORCEPROP 1 LAST WATTAGE 1/16W
J 0
(-5735 4650);
DISPLAY 0.638298 (-5735 4650);
FORCEPROP 1 LAST TOLERANCE 1%
J 0
(-5730 4700);
DISPLAY 0.638298 (-5730 4700);
FORCEPROP 1 LAST PACK_TYPE 0402LF
J 0
(-5735 4500);
DISPLAY 0.638298 (-5735 4500);
FORCEPROP 1 LAST VALUE 100K
J 0
(-5730 4750);
DISPLAY 0.638298 (-5730 4750);
FORCEPROP 1 LAST PART_NUMBER CS41002FB09
J 0
(-5735 4550);
DISPLAY 0.638298 (-5735 4550);
DISPLAY INVISIBLE (-5735 4550);
FORCEPROP 2 LAST CDS_LIB pure_quanta
J 0
(-5775 4675);
DISPLAY INVISIBLE (-5775 4675);
FORCEPROP 1 LAST PATH I7
J 0
(-5725 4850);
DISPLAY 0.978723 (-5725 4850);
PAINT WHITE (-5725 4850);
DISPLAY INVISIBLE (-5725 4850);
FORCEADD Q_RES..2
(-1750 7275);
FORCEPROP 1 LAST LOCATION R4639
J 0
(-1705 7400);
DISPLAY 0.978723 (-1705 7400);
FORCEPROP 0 LAST $SEC 1
J 0
(-1700 7450);
DISPLAY 0.680851 (-1700 7450);
PAINT MONO (-1700 7450);
DISPLAY INVISIBLE (-1700 7450);
FORCEPROP 0 LAST CDS_SEC 1
J 0
(-1700 7450);
DISPLAY 1.021277 (-1700 7450);
DISPLAY INVISIBLE (-1700 7450);
FORCEPROP 1 LASTPIN (-1750 7375) $PN 1
J 0
(-1745 7337);
DISPLAY 0.787234 (-1745 7337);
PAINT MONO (-1745 7337);
FORCEPROP 1 LASTPIN (-1750 7175) $PN 2
J 0
(-1745 7185);
DISPLAY 0.787234 (-1745 7185);
PAINT MONO (-1745 7185);
FORCEPROP 1 LAST PACK_TYPE 1206LF
J 0
(-1710 7100);
DISPLAY 0.978723 (-1710 7100);
FORCEPROP 1 LAST MATERIAL CHIP
J 0
(-1710 7200);
DISPLAY 0.978723 (-1710 7200);
FORCEPROP 1 LAST WATTAGE 1/4W
J 0
(-1710 7250);
DISPLAY 0.978723 (-1710 7250);
FORCEPROP 1 LAST TOLERANCE 1%
J 0
(-1705 7300);
DISPLAY 0.978723 (-1705 7300);
FORCEPROP 1 LAST VALUE 243
J 0
(-1705 7350);
DISPLAY 0.978723 (-1705 7350);
FORCEPROP 1 LAST PART_NUMBER CS12436F201
J 0
(-1710 7150);
DISPLAY 0.978723 (-1710 7150);
DISPLAY INVISIBLE (-1710 7150);
FORCEPROP 2 LAST CDS_LIB pure_quanta
J 0
(-1750 7275);
DISPLAY INVISIBLE (-1750 7275);
FORCEPROP 1 LAST PATH I74
J 0
(-1700 7450);
DISPLAY 0.978723 (-1700 7450);
PAINT WHITE (-1700 7450);
DISPLAY INVISIBLE (-1700 7450);
FORCEADD Q_RES..2
(-1175 7275);
FORCEPROP 1 LAST LOCATION R4640
J 0
(-1130 7400);
DISPLAY 0.978723 (-1130 7400);
FORCEPROP 0 LAST $SEC 1
J 0
(-1125 7450);
DISPLAY 0.680851 (-1125 7450);
PAINT MONO (-1125 7450);
DISPLAY INVISIBLE (-1125 7450);
FORCEPROP 0 LAST CDS_SEC 1
J 0
(-1125 7450);
DISPLAY 1.021277 (-1125 7450);
DISPLAY INVISIBLE (-1125 7450);
FORCEPROP 1 LASTPIN (-1175 7375) $PN 1
J 0
(-1170 7337);
DISPLAY 0.787234 (-1170 7337);
PAINT MONO (-1170 7337);
FORCEPROP 1 LASTPIN (-1175 7175) $PN 2
J 0
(-1170 7185);
DISPLAY 0.787234 (-1170 7185);
PAINT MONO (-1170 7185);
FORCEPROP 1 LAST WATTAGE 1/4W
J 0
(-1135 7250);
DISPLAY 0.978723 (-1135 7250);
FORCEPROP 1 LAST MATERIAL CHIP
J 0
(-1135 7200);
DISPLAY 0.978723 (-1135 7200);
FORCEPROP 1 LAST VALUE 243
J 0
(-1130 7350);
DISPLAY 0.978723 (-1130 7350);
FORCEPROP 1 LAST TOLERANCE 1%
J 0
(-1130 7300);
DISPLAY 0.978723 (-1130 7300);
FORCEPROP 1 LAST PACK_TYPE 1206LF
J 0
(-1135 7100);
DISPLAY 0.978723 (-1135 7100);
FORCEPROP 1 LAST PART_NUMBER CS12436F201
J 0
(-1135 7150);
DISPLAY 0.978723 (-1135 7150);
DISPLAY INVISIBLE (-1135 7150);
FORCEPROP 2 LAST CDS_LIB pure_quanta
J 0
(-1175 7275);
DISPLAY INVISIBLE (-1175 7275);
FORCEPROP 1 LAST PATH I75
J 0
(-1125 7450);
DISPLAY 0.978723 (-1125 7450);
PAINT WHITE (-1125 7450);
DISPLAY INVISIBLE (-1125 7450);
FORCEADD Q_RES..2
(-600 7275);
FORCEPROP 1 LAST LOCATION R4641
J 0
(-555 7400);
DISPLAY 0.978723 (-555 7400);
FORCEPROP 0 LAST $SEC 1
J 0
(-550 7450);
DISPLAY 0.680851 (-550 7450);
PAINT MONO (-550 7450);
DISPLAY INVISIBLE (-550 7450);
FORCEPROP 0 LAST CDS_SEC 1
J 0
(-550 7450);
DISPLAY 1.021277 (-550 7450);
DISPLAY INVISIBLE (-550 7450);
FORCEPROP 1 LASTPIN (-600 7375) $PN 1
J 0
(-595 7337);
DISPLAY 0.787234 (-595 7337);
PAINT MONO (-595 7337);
FORCEPROP 1 LASTPIN (-600 7175) $PN 2
J 0
(-595 7185);
DISPLAY 0.787234 (-595 7185);
PAINT MONO (-595 7185);
FORCEPROP 1 LAST PACK_TYPE 1206LF
J 0
(-560 7100);
DISPLAY 0.978723 (-560 7100);
FORCEPROP 1 LAST MATERIAL CHIP
J 0
(-560 7200);
DISPLAY 0.978723 (-560 7200);
FORCEPROP 1 LAST TOLERANCE 1%
J 0
(-555 7300);
DISPLAY 0.978723 (-555 7300);
FORCEPROP 1 LAST VALUE 243
J 0
(-555 7350);
DISPLAY 0.978723 (-555 7350);
FORCEPROP 1 LAST WATTAGE 1/4W
J 0
(-560 7250);
DISPLAY 0.978723 (-560 7250);
FORCEPROP 1 LAST PART_NUMBER CS12436F201
J 0
(-560 7150);
DISPLAY 0.978723 (-560 7150);
DISPLAY INVISIBLE (-560 7150);
FORCEPROP 2 LAST CDS_LIB pure_quanta
J 0
(-600 7275);
DISPLAY INVISIBLE (-600 7275);
FORCEPROP 1 LAST PATH I76
J 0
(-550 7450);
DISPLAY 0.978723 (-550 7450);
PAINT WHITE (-550 7450);
DISPLAY INVISIBLE (-550 7450);
FORCEADD RT9818C44GV..1
R 2
(-3750 3875);
FORCEPROP 1 LAST LOCATION U100
J 2
(-3522 4253);
DISPLAY 0.723404 (-3522 4253);
PAINT GREEN (-3522 4253);
FORCEPROP 2 LAST SEC 1
J 0
(-3525 4400);
DISPLAY 0.680851 (-3525 4400);
PAINT MONO (-3525 4400);
DISPLAY INVISIBLE (-3525 4400);
FORCEPROP 2 LASTPIN (-3375 3775) $PN 2
J 0
(-3365 3785);
DISPLAY 0.680851 (-3365 3785);
PAINT MONO (-3365 3785);
FORCEPROP 2 LASTPIN (-3375 3975) $PN 1
J 0
(-3365 3985);
DISPLAY 0.680851 (-3365 3985);
PAINT MONO (-3365 3985);
FORCEPROP 2 LASTPIN (-4125 3875) $PN 3
J 2
(-4135 3885);
DISPLAY 0.680851 (-4135 3885);
PAINT MONO (-4135 3885);
FORCEPROP 1 LAST MATERIAL IC
J 2
(-3522 4080);
DISPLAY 0.723404 (-3522 4080);
PAINT GREEN (-3522 4080);
FORCEPROP 2 LAST VALUE RT9818C-44GV
J 2
(-3525 4300);
DISPLAY 0.680851 (-3525 4300);
FORCEPROP 2 LAST PART_TYPE SMLF
J 2
(-3525 4350);
DISPLAY 0.680851 (-3525 4350);
FORCEPROP 1 LAST PART_NUMBER AL009818001
J 2
(-3522 4169);
DISPLAY 0.723404 (-3522 4169);
PAINT GREEN (-3522 4169);
DISPLAY INVISIBLE (-3522 4169);
FORCEPROP 2 LAST SEC_TYPE 
J 0
(-3525 4400);
DISPLAY 0.680851 (-3525 4400);
DISPLAY INVISIBLE (-3525 4400);
FORCEPROP 1 LAST CDS_LMAN_SYM_OUTLINE -225,200,225,-200
J 2
(-3750 3875);
DISPLAY 0.468085 (-3750 3875);
PAINT GREEN (-3750 3875);
DISPLAY INVISIBLE (-3750 3875);
FORCEPROP 1 LAST PIN_NAMES_ROTATE True
J 2
(-3750 3875);
DISPLAY 0.489362 (-3750 3875);
PAINT GREEN (-3750 3875);
DISPLAY INVISIBLE (-3750 3875);
FORCEPROP 2 LAST CDS_LIB pure_quanta
J 2
(-3750 3875);
DISPLAY INVISIBLE (-3750 3875);
FORCEPROP 1 LAST PATH I77
J 2
(-3750 3875);
DISPLAY 0.723404 (-3750 3875);
PAINT GREEN (-3750 3875);
DISPLAY INVISIBLE (-3750 3875);
FORCEADD UNIVERSAL_POWER..1
(-4275 4250);
FORCEPROP 3 LASTPIN (-4275 4200) SIG_NAME P5V\g
J 0
(-4265 4210);
DISPLAY 0.659574 (-4265 4210);
PAINT MONO (-4265 4210);
DISPLAY INVISIBLE (-4265 4210);
FORCEPROP 1 LAST HDL_POWER P5V
J 1
(-4275 4300);
DISPLAY 0.617021 (-4275 4300);
PAINT GREEN (-4275 4300);
FORCEPROP 2 LAST CDS_LIB pure_quanta_power
J 0
(-4275 4250);
DISPLAY INVISIBLE (-4275 4250);
FORCEPROP 2 LAST BOM_COST VR_SYSTEM 
J 0
(-4275 4350);
DISPLAY 0.680851 (-4275 4350);
DISPLAY INVISIBLE (-4275 4350);
FORCEPROP 1 LAST PATH I78
J 0
(-4225 4275);
DISPLAY 0.872340 (-4225 4275);
PAINT AQUA (-4225 4275);
DISPLAY INVISIBLE (-4225 4275);
FORCEADD Q_CAP..1
(-4275 3525);
FORCEPROP 1 LAST LOCATION C6122
J 0
(-4225 3625);
DISPLAY 0.808511 (-4225 3625);
FORCEPROP 0 LAST $SEC 1
J 0
(-4225 3675);
DISPLAY 0.680851 (-4225 3675);
PAINT MONO (-4225 3675);
DISPLAY INVISIBLE (-4225 3675);
FORCEPROP 0 LAST CDS_SEC 1
J 0
(-4225 3675);
DISPLAY 0.680851 (-4225 3675);
DISPLAY INVISIBLE (-4225 3675);
FORCEPROP 1 LASTPIN (-4275 3625) $PN 1
J 0
(-4265 3605);
DISPLAY 0.787234 (-4265 3605);
PAINT MONO (-4265 3605);
FORCEPROP 1 LASTPIN (-4275 3425) $PN 2
J 0
(-4265 3405);
DISPLAY 0.787234 (-4265 3405);
PAINT MONO (-4265 3405);
FORCEPROP 1 LAST VALUE 100NF
J 0
(-4225 3575);
DISPLAY 0.638298 (-4225 3575);
FORCEPROP 1 LAST VOLTAGE 50V
J 0
(-4225 3525);
DISPLAY 0.638298 (-4225 3525);
FORCEPROP 1 LAST TOLERANCE 10%
J 0
(-4225 3475);
DISPLAY 0.638298 (-4225 3475);
FORCEPROP 1 LAST MATERIAL X7R
J 0
(-4225 3425);
DISPLAY 0.638298 (-4225 3425);
FORCEPROP 1 LAST PACK_TYPE C0402
J 0
(-4225 3325);
DISPLAY 0.638298 (-4225 3325);
FORCEPROP 1 LAST PART_NUMBER CH4106K1B01
J 0
(-4225 3375);
DISPLAY 0.638298 (-4225 3375);
DISPLAY INVISIBLE (-4225 3375);
FORCEPROP 2 LAST CDS_LIB pure_quanta
J 0
(-4275 3525);
DISPLAY INVISIBLE (-4275 3525);
FORCEPROP 1 LAST PATH I79
J 0
(-4225 3675);
DISPLAY 0.978723 (-4225 3675);
PAINT WHITE (-4225 3675);
DISPLAY INVISIBLE (-4225 3675);
FORCEADD UNIVERSAL_GND..1
(-5125 4525);
FORCEPROP 3 LASTPIN (-5125 4575) SIG_NAME GND\g
J 0
(-5115 4585);
DISPLAY 0.659574 (-5115 4585);
PAINT MONO (-5115 4585);
DISPLAY INVISIBLE (-5115 4585);
FORCEPROP 2 LAST CDS_LIB pure_quanta_power
J 0
(-5125 4525);
DISPLAY INVISIBLE (-5125 4525);
FORCEPROP 2 LAST BOM_COST VR_SYSTEM 
J 0
(-5425 4600);
DISPLAY 0.680851 (-5425 4600);
DISPLAY INVISIBLE (-5425 4600);
FORCEPROP 0 LAST VOLTAGE 0
J 0
(-5125 4525);
PAINT SKYBLUE (-5125 4525);
DISPLAY INVISIBLE (-5125 4525);
FORCEPROP 1 LAST HDL_POWER GND
J 1
(-5100 4450);
DISPLAY 0.872340 (-5100 4450);
PAINT GREEN (-5100 4450);
DISPLAY INVISIBLE (-5100 4450);
FORCEPROP 1 LAST PATH I8
J 0
(-5050 4525);
DISPLAY 0.872340 (-5050 4525);
PAINT AQUA (-5050 4525);
DISPLAY INVISIBLE (-5050 4525);
FORCEADD UNIVERSAL_GND..1
(-4275 3150);
FORCEPROP 3 LASTPIN (-4275 3200) SIG_NAME GND\g
J 0
(-4265 3210);
DISPLAY 0.659574 (-4265 3210);
PAINT MONO (-4265 3210);
DISPLAY INVISIBLE (-4265 3210);
FORCEPROP 0 LAST VOLTAGE 0
J 0
(-4275 3150);
PAINT SKYBLUE (-4275 3150);
DISPLAY INVISIBLE (-4275 3150);
FORCEPROP 2 LAST BOM_COST VR_SYSTEM 
J 0
(-4575 3225);
DISPLAY 0.680851 (-4575 3225);
DISPLAY INVISIBLE (-4575 3225);
FORCEPROP 2 LAST CDS_LIB pure_quanta_power
J 0
(-4275 3150);
DISPLAY INVISIBLE (-4275 3150);
FORCEPROP 1 LAST HDL_POWER GND
J 1
(-4250 3075);
DISPLAY 0.872340 (-4250 3075);
PAINT GREEN (-4250 3075);
DISPLAY INVISIBLE (-4250 3075);
FORCEPROP 1 LAST PATH I80
J 0
(-4200 3150);
DISPLAY 0.872340 (-4200 3150);
PAINT AQUA (-4200 3150);
DISPLAY INVISIBLE (-4200 3150);
FORCEADD UNIVERSAL_GND..1
(-3300 3475);
FORCEPROP 3 LASTPIN (-3300 3525) SIG_NAME GND\g
J 0
(-3290 3535);
DISPLAY 0.659574 (-3290 3535);
PAINT MONO (-3290 3535);
DISPLAY INVISIBLE (-3290 3535);
FORCEPROP 2 LAST CDS_LIB pure_quanta_power
J 0
(-3300 3475);
DISPLAY INVISIBLE (-3300 3475);
FORCEPROP 2 LAST BOM_COST VR_SYSTEM 
J 0
(-3600 3550);
DISPLAY 0.680851 (-3600 3550);
DISPLAY INVISIBLE (-3600 3550);
FORCEPROP 0 LAST VOLTAGE 0
J 0
(-3300 3475);
PAINT SKYBLUE (-3300 3475);
DISPLAY INVISIBLE (-3300 3475);
FORCEPROP 1 LAST HDL_POWER GND
J 1
(-3275 3400);
DISPLAY 0.872340 (-3275 3400);
PAINT GREEN (-3275 3400);
DISPLAY INVISIBLE (-3275 3400);
FORCEPROP 1 LAST PATH I81
J 0
(-3225 3475);
DISPLAY 0.872340 (-3225 3475);
PAINT AQUA (-3225 3475);
DISPLAY INVISIBLE (-3225 3475);
FORCEADD Q_RES..2
(-2875 4250);
FORCEPROP 1 LAST LOCATION R479
J 0
(-2830 4375);
DISPLAY 0.808511 (-2830 4375);
FORCEPROP 2 LAST SEC 1
J 0
(-2825 4475);
DISPLAY 0.680851 (-2825 4475);
PAINT MONO (-2825 4475);
DISPLAY INVISIBLE (-2825 4475);
FORCEPROP 1 LASTPIN (-2875 4350) $PN 1
J 0
(-2870 4312);
DISPLAY 0.787234 (-2870 4312);
PAINT MONO (-2870 4312);
FORCEPROP 1 LASTPIN (-2875 4150) $PN 2
J 0
(-2870 4160);
DISPLAY 0.787234 (-2870 4160);
PAINT MONO (-2870 4160);
FORCEPROP 1 LAST WATTAGE 1/16W
J 0
(-2835 4225);
DISPLAY 0.638298 (-2835 4225);
FORCEPROP 1 LAST VALUE 10K
J 0
(-2830 4325);
DISPLAY 0.638298 (-2830 4325);
FORCEPROP 1 LAST TOLERANCE 1%
J 0
(-2830 4275);
DISPLAY 0.638298 (-2830 4275);
FORCEPROP 1 LAST MATERIAL CHIP
J 0
(-2835 4175);
DISPLAY 0.638298 (-2835 4175);
FORCEPROP 1 LAST PACK_TYPE 0402LF
J 0
(-2835 4075);
DISPLAY 0.638298 (-2835 4075);
FORCEPROP 1 LAST PART_NUMBER CS31002FB08
J 0
(-2835 4125);
DISPLAY 0.638298 (-2835 4125);
DISPLAY INVISIBLE (-2835 4125);
FORCEPROP 2 LAST CDS_LIB pure_quanta
J 0
(-2875 4250);
DISPLAY INVISIBLE (-2875 4250);
FORCEPROP 2 LAST SEC_TYPE 0402LF
J 0
(-2825 4475);
DISPLAY 0.680851 (-2825 4475);
DISPLAY INVISIBLE (-2825 4475);
FORCEPROP 1 LAST PATH I83
J 0
(-2825 4425);
DISPLAY 0.978723 (-2825 4425);
PAINT WHITE (-2825 4425);
DISPLAY INVISIBLE (-2825 4425);
FORCEADD Q_RES..2
R 2
(-2800 3725);
FORCEPROP 1 LAST LOCATION R480
J 2
(-2845 3850);
DISPLAY 0.808511 (-2845 3850);
FORCEPROP 2 LAST SEC 1
J 2
(-2850 3950);
DISPLAY 0.680851 (-2850 3950);
PAINT MONO (-2850 3950);
DISPLAY INVISIBLE (-2850 3950);
FORCEPROP 1 LASTPIN (-2800 3825) $PN 1
J 2
(-2805 3787);
DISPLAY 0.787234 (-2805 3787);
PAINT MONO (-2805 3787);
FORCEPROP 1 LASTPIN (-2800 3625) $PN 2
J 2
(-2805 3635);
DISPLAY 0.787234 (-2805 3635);
PAINT MONO (-2805 3635);
FORCEPROP 1 LAST TOLERANCE 1%
J 2
(-2845 3750);
DISPLAY 0.638298 (-2845 3750);
FORCEPROP 1 LAST VALUE 100K
J 2
(-2845 3800);
DISPLAY 0.638298 (-2845 3800);
FORCEPROP 1 LAST WATTAGE 1/16W
J 2
(-2840 3700);
DISPLAY 0.638298 (-2840 3700);
FORCEPROP 1 LAST MATERIAL CHIP
J 2
(-2840 3650);
DISPLAY 0.638298 (-2840 3650);
FORCEPROP 1 LAST PACK_TYPE 0402LF
J 2
(-2840 3550);
DISPLAY 0.638298 (-2840 3550);
FORCEPROP 1 LAST PART_NUMBER CS41002FB09
J 2
(-2840 3600);
DISPLAY 0.638298 (-2840 3600);
DISPLAY INVISIBLE (-2840 3600);
FORCEPROP 2 LAST SEC_TYPE 0402LF
J 2
(-2850 3950);
DISPLAY 0.680851 (-2850 3950);
DISPLAY INVISIBLE (-2850 3950);
FORCEPROP 2 LAST CDS_LIB pure_quanta
J 2
(-2800 3725);
DISPLAY INVISIBLE (-2800 3725);
FORCEPROP 1 LAST PATH I84
J 2
(-2850 3900);
DISPLAY 0.978723 (-2850 3900);
PAINT WHITE (-2850 3900);
DISPLAY INVISIBLE (-2850 3900);
FORCEADD UNIVERSAL_POWER..1
(-2875 4550);
FORCEPROP 3 LASTPIN (-2875 4500) SIG_NAME P5V\g
J 0
(-2865 4510);
DISPLAY 0.659574 (-2865 4510);
PAINT MONO (-2865 4510);
DISPLAY INVISIBLE (-2865 4510);
FORCEPROP 1 LAST HDL_POWER P5V
J 1
(-2875 4600);
DISPLAY 0.617021 (-2875 4600);
PAINT GREEN (-2875 4600);
FORCEPROP 2 LAST CDS_LIB pure_quanta_power
J 0
(-2875 4550);
DISPLAY INVISIBLE (-2875 4550);
FORCEPROP 2 LAST BOM_COST VR_SYSTEM 
J 0
(-2875 4650);
DISPLAY 0.680851 (-2875 4650);
DISPLAY INVISIBLE (-2875 4650);
FORCEPROP 1 LAST PATH I85
J 0
(-2825 4575);
DISPLAY 0.872340 (-2825 4575);
PAINT AQUA (-2825 4575);
DISPLAY INVISIBLE (-2825 4575);
FORCEADD UNIVERSAL_GND..1
(-2800 3450);
FORCEPROP 3 LASTPIN (-2800 3500) SIG_NAME GND\g
J 0
(-2790 3510);
DISPLAY 0.659574 (-2790 3510);
PAINT MONO (-2790 3510);
DISPLAY INVISIBLE (-2790 3510);
FORCEPROP 0 LAST VOLTAGE 0
J 0
(-2800 3450);
PAINT SKYBLUE (-2800 3450);
DISPLAY INVISIBLE (-2800 3450);
FORCEPROP 2 LAST BOM_COST VR_SYSTEM 
J 0
(-3100 3525);
DISPLAY 0.680851 (-3100 3525);
DISPLAY INVISIBLE (-3100 3525);
FORCEPROP 2 LAST CDS_LIB pure_quanta_power
J 0
(-2800 3450);
DISPLAY INVISIBLE (-2800 3450);
FORCEPROP 1 LAST HDL_POWER GND
J 1
(-2775 3375);
DISPLAY 0.872340 (-2775 3375);
PAINT GREEN (-2775 3375);
DISPLAY INVISIBLE (-2775 3375);
FORCEPROP 1 LAST PATH I86
J 0
(-2725 3450);
DISPLAY 0.872340 (-2725 3450);
PAINT AQUA (-2725 3450);
DISPLAY INVISIBLE (-2725 3450);
FORCEADD Q_RES..1
(-2275 3975);
FORCEPROP 1 LAST LOCATION R490
J 0
(-2525 4000);
DISPLAY 0.808511 (-2525 4000);
FORCEPROP 2 LAST SEC 1
J 0
(-2325 4175);
DISPLAY 0.680851 (-2325 4175);
PAINT MONO (-2325 4175);
DISPLAY INVISIBLE (-2325 4175);
FORCEPROP 1 LASTPIN (-2375 3975) $PN 1
J 0
(-2363 3987);
DISPLAY 0.787234 (-2363 3987);
PAINT MONO (-2363 3987);
FORCEPROP 1 LASTPIN (-2175 3975) $PN 2
J 0
(-2213 3987);
DISPLAY 0.787234 (-2213 3987);
PAINT MONO (-2213 3987);
FORCEPROP 1 LAST TOLERANCE 5%
J 0
(-2075 3975);
DISPLAY 0.638298 (-2075 3975);
FORCEPROP 1 LAST MATERIAL EMPTY
J 0
(-2500 3925);
DISPLAY 0.638298 (-2500 3925);
FORCEPROP 1 LAST VALUE 0
J 2
(-2100 3975);
DISPLAY 0.638298 (-2100 3975);
FORCEPROP 1 LAST PACK_TYPE 0402LF
J 0
(-2175 3925);
DISPLAY 0.638298 (-2175 3925);
FORCEPROP 1 LAST PART_NUMBER CS00002JB13
J 0
(-2425 4050);
DISPLAY 0.638298 (-2425 4050);
DISPLAY INVISIBLE (-2425 4050);
FORCEPROP 2 LAST SEC_TYPE 0402LF
J 0
(-2325 4175);
DISPLAY 0.680851 (-2325 4175);
DISPLAY INVISIBLE (-2325 4175);
FORCEPROP 1 LAST WATTAGE 1/16W
J 2
(-2300 3825);
DISPLAY 0.978723 (-2300 3825);
DISPLAY INVISIBLE (-2300 3825);
FORCEPROP 2 LAST CDS_LIB pure_quanta
J 0
(-2275 3975);
DISPLAY INVISIBLE (-2275 3975);
FORCEPROP 1 LAST PATH I88
J 0
(-2325 4125);
DISPLAY 0.978723 (-2325 4125);
PAINT WHITE (-2325 4125);
DISPLAY INVISIBLE (-2325 4125);
FORCEADD MOSFET_NCH_DUAL..1
(-5175 5000);
FORCEPROP 1 LAST LOCATION Q37
J 0
(-5024 4974);
DISPLAY 0.723404 (-5024 4974);
PAINT GREEN (-5024 4974);
FORCEPROP 2 LAST $SEC 1
J 0
(-5025 5150);
DISPLAY 0.680851 (-5025 5150);
PAINT MONO (-5025 5150);
DISPLAY INVISIBLE (-5025 5150);
FORCEPROP 2 LAST CDS_SEC 1
J 0
(-5025 5150);
DISPLAY 1.021277 (-5025 5150);
DISPLAY INVISIBLE (-5025 5150);
FORCEPROP 2 LASTPIN (-5125 5200) $PN 6
R 1
J 0
(-5135 5210);
DISPLAY 0.808511 (-5135 5210);
FORCEPROP 2 LASTPIN (-5375 4950) $PN 2
J 2
(-5385 4960);
DISPLAY 0.808511 (-5385 4960);
FORCEPROP 2 LASTPIN (-5125 4800) $PN 1
R 1
J 2
(-5135 4790);
DISPLAY 0.808511 (-5135 4790);
FORCEPROP 2 LAST PART_TYPE SMLF
J 0
(-5025 5100);
DISPLAY 0.808511 (-5025 5100);
FORCEPROP 1 LAST MATERIAL IC
J 0
(-5024 4849);
DISPLAY 0.723404 (-5024 4849);
PAINT GREEN (-5024 4849);
FORCEPROP 2 LAST VALUE PJT138K
J 0
(-5025 5050);
DISPLAY 0.808511 (-5025 5050);
FORCEPROP 1 LAST PART_NUMBER BAM138K0003
J 0
(-5024 4914);
DISPLAY 0.723404 (-5024 4914);
PAINT GREEN (-5024 4914);
DISPLAY INVISIBLE (-5024 4914);
FORCEPROP 1 LAST NEEDS_NO_SIZE TRUE
J 0
(-5175 4999);
DISPLAY 0.468085 (-5175 4999);
PAINT GREEN (-5175 4999);
DISPLAY INVISIBLE (-5175 4999);
FORCEPROP 1 LAST CDS_LMAN_SYM_OUTLINE -150,150,150,-150
J 0
(-5175 5000);
DISPLAY 0.468085 (-5175 5000);
PAINT GREEN (-5175 5000);
DISPLAY INVISIBLE (-5175 5000);
FORCEPROP 2 LAST CDS_LIB pure_quanta
J 0
(-5175 5000);
PAINT MONO (-5175 5000);
DISPLAY INVISIBLE (-5175 5000);
FORCEPROP 1 LAST PATH I9
J 0
(-5175 5000);
DISPLAY 0.723404 (-5175 5000);
PAINT GREEN (-5175 5000);
DISPLAY INVISIBLE (-5175 5000);
FORCEADD OFFPAGE..1
(-3825 4775);
FORCEPROP 2 LAST $XR0 81 
J 0
(-4076 4775);
DISPLAY 0.638298 (-4076 4775);
PAINT MONO (-4076 4775);
FORCEPROP 2 LAST BOM_COST VR_SYSTEM 
J 0
(-4100 4825);
DISPLAY 0.617021 (-4100 4825);
PAINT PURPLE (-4100 4825);
DISPLAY INVISIBLE (-4100 4825);
FORCEPROP 2 LAST CDS_LIB standard
J 0
(-3825 4775);
DISPLAY INVISIBLE (-3825 4775);
FORCEPROP 1 LAST OFFPAGE TRUE
J 0
(-3500 4650);
DISPLAY 1.042553 (-3500 4650);
PAINT GREEN (-3500 4650);
DISPLAY INVISIBLE (-3500 4650);
FORCEPROP 1 LAST COMMENT_BODY TRUE
J 0
(-3700 4675);
DISPLAY 1.042553 (-3700 4675);
PAINT GREEN (-3700 4675);
DISPLAY INVISIBLE (-3700 4675);
FORCEPROP 2 LAST PATH I90
J 0
(-4025 4825);
DISPLAY 0.680851 (-4025 4825);
DISPLAY INVISIBLE (-4025 4825);
FORCEADD Q_RES..2
R 2
(-3200 4575);
FORCEPROP 1 LAST LOCATION R6050
J 2
(-3245 4700);
DISPLAY 0.638298 (-3245 4700);
FORCEPROP 2 LAST SEC 1
J 0
(-3250 4800);
DISPLAY 0.680851 (-3250 4800);
PAINT MONO (-3250 4800);
DISPLAY INVISIBLE (-3250 4800);
FORCEPROP 1 LASTPIN (-3200 4675) $PN 1
J 2
(-3205 4637);
DISPLAY 0.787234 (-3205 4637);
PAINT MONO (-3205 4637);
FORCEPROP 1 LASTPIN (-3200 4475) $PN 2
J 2
(-3205 4485);
DISPLAY 0.787234 (-3205 4485);
PAINT MONO (-3205 4485);
FORCEPROP 1 LAST TOLERANCE 1%
J 2
(-3245 4600);
DISPLAY 0.638298 (-3245 4600);
FORCEPROP 1 LAST VALUE 100K
J 2
(-3245 4650);
DISPLAY 0.638298 (-3245 4650);
FORCEPROP 1 LAST MATERIAL EMPTY
J 2
(-3250 4550);
DISPLAY 0.638298 (-3250 4550);
FORCEPROP 1 LAST PACK_TYPE 0402LF
J 2
(-3250 4450);
DISPLAY 0.638298 (-3250 4450);
FORCEPROP 1 LAST PART_NUMBER CS41002FB09
J 2
(-3250 4500);
DISPLAY 0.638298 (-3250 4500);
DISPLAY INVISIBLE (-3250 4500);
FORCEPROP 1 LAST WATTAGE 1/16W
J 2
(-3240 4550);
DISPLAY 0.638298 (-3240 4550);
DISPLAY INVISIBLE (-3240 4550);
FORCEPROP 2 LAST CDS_LIB pure_quanta
J 2
(-3200 4575);
DISPLAY INVISIBLE (-3200 4575);
FORCEPROP 2 LAST SEC_TYPE 0402LF
J 0
(-3250 4800);
DISPLAY 0.680851 (-3250 4800);
DISPLAY INVISIBLE (-3250 4800);
FORCEPROP 1 LAST PATH I91
J 2
(-3250 4750);
DISPLAY 0.978723 (-3250 4750);
PAINT WHITE (-3250 4750);
DISPLAY INVISIBLE (-3250 4750);
FORCEADD UNIVERSAL_GND..1
(-3200 4350);
FORCEPROP 3 LASTPIN (-3200 4400) SIG_NAME GND\g
J 0
(-3190 4410);
DISPLAY 0.659574 (-3190 4410);
PAINT MONO (-3190 4410);
DISPLAY INVISIBLE (-3190 4410);
FORCEPROP 2 LAST BOM_COST VR_SYSTEM 
J 0
(-3500 4425);
DISPLAY 0.680851 (-3500 4425);
DISPLAY INVISIBLE (-3500 4425);
FORCEPROP 0 LAST VOLTAGE 0
J 0
(-3200 4350);
PAINT SKYBLUE (-3200 4350);
DISPLAY INVISIBLE (-3200 4350);
FORCEPROP 2 LAST CDS_LIB pure_quanta_power
J 0
(-3200 4350);
DISPLAY INVISIBLE (-3200 4350);
FORCEPROP 1 LAST HDL_POWER GND
J 1
(-3175 4275);
DISPLAY 0.872340 (-3175 4275);
PAINT GREEN (-3175 4275);
DISPLAY INVISIBLE (-3175 4275);
FORCEPROP 1 LAST PATH I92
J 0
(-3125 4350);
DISPLAY 0.872340 (-3125 4350);
PAINT AQUA (-3125 4350);
DISPLAY INVISIBLE (-3125 4350);
FORCEADD Q_RES..2
(-3175 5075);
FORCEPROP 1 LAST LOCATION R496
J 0
(-3130 5200);
DISPLAY 0.787234 (-3130 5200);
FORCEPROP 0 LAST $SEC 1
J 0
(-3125 5250);
DISPLAY 0.680851 (-3125 5250);
PAINT MONO (-3125 5250);
DISPLAY INVISIBLE (-3125 5250);
FORCEPROP 0 LAST CDS_SEC 1
J 0
(-3125 5250);
DISPLAY 0.680851 (-3125 5250);
DISPLAY INVISIBLE (-3125 5250);
FORCEPROP 1 LASTPIN (-3175 5175) $PN 1
J 0
(-3170 5137);
DISPLAY 0.787234 (-3170 5137);
PAINT MONO (-3170 5137);
FORCEPROP 1 LASTPIN (-3175 4975) $PN 2
J 0
(-3170 4985);
DISPLAY 0.787234 (-3170 4985);
PAINT MONO (-3170 4985);
FORCEPROP 1 LAST PACK_TYPE 0402LF
J 0
(-3135 4900);
DISPLAY 0.787234 (-3135 4900);
FORCEPROP 1 LAST VALUE 10K
J 0
(-3130 5150);
DISPLAY 0.787234 (-3130 5150);
FORCEPROP 1 LAST MATERIAL EMPTY
J 0
(-3135 5000);
DISPLAY 0.787234 (-3135 5000);
FORCEPROP 1 LAST WATTAGE 1/16W
J 0
(-3135 5050);
DISPLAY 0.787234 (-3135 5050);
FORCEPROP 1 LAST TOLERANCE 1%
J 0
(-3130 5100);
DISPLAY 0.787234 (-3130 5100);
FORCEPROP 1 LAST PART_NUMBER CS31002FB08
J 0
(-3135 4950);
DISPLAY 0.787234 (-3135 4950);
DISPLAY INVISIBLE (-3135 4950);
FORCEPROP 2 LAST CDS_LIB pure_quanta
J 0
(-3175 5075);
DISPLAY INVISIBLE (-3175 5075);
FORCEPROP 1 LAST PATH I93
J 0
(-3125 5250);
DISPLAY 0.978723 (-3125 5250);
PAINT WHITE (-3125 5250);
DISPLAY INVISIBLE (-3125 5250);
FORCEADD P1V0_AUX..1
(-3175 5350);
FORCEPROP 3 LASTPIN (-3175 5300) SIG_NAME P3V3_AUX\g
J 0
(-3165 5310);
DISPLAY 0.659574 (-3165 5310);
PAINT MONO (-3165 5310);
DISPLAY INVISIBLE (-3165 5310);
FORCEPROP 1 LAST HDL_POWER P3V3_AUX
J 1
(-3165 5390);
DISPLAY 0.617021 (-3165 5390);
PAINT GREEN (-3165 5390);
FORCEPROP 2 LAST BOM_COST VR_SYSTEM 
J 0
(-3149 5426);
DISPLAY 0.680851 (-3149 5426);
DISPLAY INVISIBLE (-3149 5426);
FORCEPROP 2 LAST CDS_LIB pure_quanta_power
J 0
(-3175 5350);
DISPLAY INVISIBLE (-3175 5350);
FORCEPROP 1 LAST PATH I94
J 0
(-3125 5375);
DISPLAY 0.872340 (-3125 5375);
PAINT AQUA (-3125 5375);
DISPLAY INVISIBLE (-3125 5375);
FORCEADD Q_RES..1
(-2475 4775);
FORCEPROP 1 LAST LOCATION R487
J 0
(-2750 4775);
DISPLAY 0.808511 (-2750 4775);
FORCEPROP 2 LAST SEC 1
J 0
(-2525 4975);
DISPLAY 0.680851 (-2525 4975);
PAINT MONO (-2525 4975);
DISPLAY INVISIBLE (-2525 4975);
FORCEPROP 1 LASTPIN (-2575 4775) $PN 1
J 0
(-2563 4787);
DISPLAY 0.787234 (-2563 4787);
PAINT MONO (-2563 4787);
FORCEPROP 1 LASTPIN (-2375 4775) $PN 2
J 0
(-2413 4787);
DISPLAY 0.787234 (-2413 4787);
PAINT MONO (-2413 4787);
FORCEPROP 1 LAST PACK_TYPE 0402LF
J 0
(-2375 4725);
DISPLAY 0.638298 (-2375 4725);
FORCEPROP 1 LAST VALUE 0
J 2
(-2325 4775);
DISPLAY 0.638298 (-2325 4775);
FORCEPROP 1 LAST MATERIAL CHIP
J 0
(-2675 4725);
DISPLAY 0.638298 (-2675 4725);
FORCEPROP 1 LAST TOLERANCE 5%
J 0
(-2300 4775);
DISPLAY 0.638298 (-2300 4775);
FORCEPROP 1 LAST PART_NUMBER CS00002JB13
J 0
(-2625 4825);
DISPLAY 0.638298 (-2625 4825);
DISPLAY INVISIBLE (-2625 4825);
FORCEPROP 2 LAST CDS_LIB pure_quanta
J 0
(-2475 4775);
DISPLAY INVISIBLE (-2475 4775);
FORCEPROP 2 LAST SEC_TYPE 0402LF
J 0
(-2525 4975);
DISPLAY 0.680851 (-2525 4975);
DISPLAY INVISIBLE (-2525 4975);
FORCEPROP 1 LAST WATTAGE 1/16W
J 2
(-2500 4625);
DISPLAY 0.978723 (-2500 4625);
DISPLAY INVISIBLE (-2500 4625);
FORCEPROP 1 LAST PATH I95
J 0
(-2525 4925);
DISPLAY 0.978723 (-2525 4925);
PAINT WHITE (-2525 4925);
DISPLAY INVISIBLE (-2525 4925);
FORCEADD Q_RES..1
(-2500 2500);
FORCEPROP 1 LAST LOCATION R482
J 0
(-2575 2575);
DISPLAY 0.978723 (-2575 2575);
FORCEPROP 2 LAST SEC 1
J 0
(-2550 2700);
DISPLAY 0.680851 (-2550 2700);
PAINT MONO (-2550 2700);
DISPLAY INVISIBLE (-2550 2700);
FORCEPROP 1 LASTPIN (-2600 2500) $PN 1
J 0
(-2588 2512);
DISPLAY 0.787234 (-2588 2512);
PAINT MONO (-2588 2512);
FORCEPROP 1 LASTPIN (-2400 2500) $PN 2
J 0
(-2438 2512);
DISPLAY 0.787234 (-2438 2512);
PAINT MONO (-2438 2512);
FORCEPROP 1 LAST VALUE 0
J 2
(-2350 2500);
DISPLAY 0.638298 (-2350 2500);
FORCEPROP 1 LAST TOLERANCE 5%
J 0
(-2325 2500);
DISPLAY 0.638298 (-2325 2500);
FORCEPROP 1 LAST PACK_TYPE 0402LF
J 0
(-2400 2450);
DISPLAY 0.638298 (-2400 2450);
FORCEPROP 1 LAST MATERIAL CHIP
J 0
(-2700 2450);
DISPLAY 0.638298 (-2700 2450);
FORCEPROP 1 LAST PART_NUMBER CS00002JB13
J 0
(-2650 2425);
DISPLAY 0.638298 (-2650 2425);
DISPLAY INVISIBLE (-2650 2425);
FORCEPROP 1 LAST WATTAGE 1/16W
J 2
(-2525 2350);
DISPLAY 0.978723 (-2525 2350);
DISPLAY INVISIBLE (-2525 2350);
FORCEPROP 2 LAST CDS_LIB pure_quanta
J 0
(-2500 2500);
DISPLAY INVISIBLE (-2500 2500);
FORCEPROP 2 LAST SEC_TYPE 0402LF
J 0
(-2550 2700);
DISPLAY 0.680851 (-2550 2700);
DISPLAY INVISIBLE (-2550 2700);
FORCEPROP 1 LAST PATH I96
J 0
(-2550 2650);
DISPLAY 0.978723 (-2550 2650);
PAINT WHITE (-2550 2650);
DISPLAY INVISIBLE (-2550 2650);
FORCEADD MOSFET_NCH_DUAL..1
(-1500 2550);
FORCEPROP 1 LAST LOCATION Q1
J 0
(-1349 2524);
DISPLAY 0.723404 (-1349 2524);
PAINT GREEN (-1349 2524);
FORCEPROP 2 LAST SEC 1
J 0
(-1325 2675);
DISPLAY 0.680851 (-1325 2675);
PAINT MONO (-1325 2675);
DISPLAY INVISIBLE (-1325 2675);
FORCEPROP 2 LASTPIN (-1450 2750) $PN 6
R 1
J 0
(-1460 2760);
DISPLAY 0.680851 (-1460 2760);
PAINT MONO (-1460 2760);
FORCEPROP 2 LASTPIN (-1700 2500) $PN 2
J 2
(-1710 2510);
DISPLAY 0.680851 (-1710 2510);
PAINT MONO (-1710 2510);
FORCEPROP 2 LASTPIN (-1450 2350) $PN 1
R 1
J 2
(-1460 2340);
DISPLAY 0.680851 (-1460 2340);
PAINT MONO (-1460 2340);
FORCEPROP 2 LAST VALUE PJT138K
J 0
(-1325 2575);
DISPLAY 0.680851 (-1325 2575);
FORCEPROP 2 LAST PART_TYPE SMLF
J 0
(-1325 2625);
DISPLAY 0.680851 (-1325 2625);
FORCEPROP 1 LAST MATERIAL IC
J 0
(-1349 2399);
DISPLAY 0.723404 (-1349 2399);
PAINT GREEN (-1349 2399);
FORCEPROP 1 LAST PART_NUMBER BAM138K0003
J 0
(-1349 2464);
DISPLAY 0.723404 (-1349 2464);
PAINT GREEN (-1349 2464);
DISPLAY INVISIBLE (-1349 2464);
FORCEPROP 2 LAST SEC_TYPE 
J 0
(-1325 2675);
DISPLAY 0.680851 (-1325 2675);
DISPLAY INVISIBLE (-1325 2675);
FORCEPROP 2 LAST CDS_LIB pure_quanta
J 0
(-1500 2550);
DISPLAY INVISIBLE (-1500 2550);
FORCEPROP 1 LAST NEEDS_NO_SIZE TRUE
J 0
(-1500 2549);
DISPLAY 0.468085 (-1500 2549);
PAINT GREEN (-1500 2549);
DISPLAY INVISIBLE (-1500 2549);
FORCEPROP 1 LAST CDS_LMAN_SYM_OUTLINE -150,150,150,-150
J 0
(-1500 2550);
DISPLAY 0.468085 (-1500 2550);
PAINT GREEN (-1500 2550);
DISPLAY INVISIBLE (-1500 2550);
FORCEPROP 1 LAST PATH I97
J 0
(-1500 2550);
DISPLAY 0.723404 (-1500 2550);
PAINT GREEN (-1500 2550);
DISPLAY INVISIBLE (-1500 2550);
FORCEADD MOSFET_NCH_DUAL..2
(250 2900);
FORCEPROP 1 LAST LOCATION Q1
J 0
(401 2876);
DISPLAY 0.723404 (401 2876);
PAINT GREEN (401 2876);
FORCEPROP 2 LAST SEC 2
J 0
(425 3025);
DISPLAY 0.680851 (425 3025);
PAINT MONO (425 3025);
DISPLAY INVISIBLE (425 3025);
FORCEPROP 2 LASTPIN (300 3100) $PN 3
R 1
J 0
(290 3110);
DISPLAY 0.680851 (290 3110);
PAINT MONO (290 3110);
FORCEPROP 2 LASTPIN (50 2850) $PN 5
J 2
(40 2860);
DISPLAY 0.680851 (40 2860);
PAINT MONO (40 2860);
FORCEPROP 2 LASTPIN (300 2700) $PN 4
R 1
J 2
(290 2690);
DISPLAY 0.680851 (290 2690);
PAINT MONO (290 2690);
FORCEPROP 2 LAST PART_TYPE SMLF
J 0
(425 2975);
DISPLAY 0.680851 (425 2975);
FORCEPROP 2 LAST VALUE PJT138K
J 0
(425 2925);
DISPLAY 0.680851 (425 2925);
FORCEPROP 1 LAST MATERIAL IC
J 0
(401 2751);
DISPLAY 0.723404 (401 2751);
PAINT GREEN (401 2751);
FORCEPROP 1 LAST PART_NUMBER BAM138K0003
J 0
(401 2806);
DISPLAY 0.723404 (401 2806);
PAINT GREEN (401 2806);
DISPLAY INVISIBLE (401 2806);
FORCEPROP 1 LAST CDS_LMAN_SYM_OUTLINE -150,150,150,-150
J 0
(250 2900);
DISPLAY 0.468085 (250 2900);
PAINT GREEN (250 2900);
DISPLAY INVISIBLE (250 2900);
FORCEPROP 1 LAST NEEDS_NO_SIZE TRUE
J 0
(400 2791);
DISPLAY 0.468085 (400 2791);
PAINT GREEN (400 2791);
DISPLAY INVISIBLE (400 2791);
FORCEPROP 2 LAST CDS_LIB pure_quanta
J 0
(250 2900);
DISPLAY INVISIBLE (250 2900);
FORCEPROP 2 LAST SEC_TYPE 
J 0
(425 3025);
DISPLAY 0.680851 (425 3025);
DISPLAY INVISIBLE (425 3025);
FORCEPROP 1 LAST PATH I98
J 0
(400 2750);
DISPLAY 0.723404 (400 2750);
PAINT GREEN (400 2750);
DISPLAY INVISIBLE (400 2750);
FORCEADD Q_RES..2
R 2
(-1450 3000);
FORCEPROP 1 LAST LOCATION R492
J 2
(-1495 3125);
DISPLAY 0.978723 (-1495 3125);
FORCEPROP 2 LAST SEC 1
J 2
(-1500 3225);
DISPLAY 0.680851 (-1500 3225);
PAINT MONO (-1500 3225);
DISPLAY INVISIBLE (-1500 3225);
FORCEPROP 1 LASTPIN (-1450 3100) $PN 1
J 2
(-1455 3062);
DISPLAY 0.787234 (-1455 3062);
PAINT MONO (-1455 3062);
FORCEPROP 1 LASTPIN (-1450 2900) $PN 2
J 2
(-1455 2910);
DISPLAY 0.787234 (-1455 2910);
PAINT MONO (-1455 2910);
FORCEPROP 1 LAST PACK_TYPE 0402LF
J 2
(-1490 2825);
DISPLAY 0.978723 (-1490 2825);
FORCEPROP 1 LAST MATERIAL CHIP
J 2
(-1490 2925);
DISPLAY 0.978723 (-1490 2925);
FORCEPROP 1 LAST WATTAGE 1/16W
J 2
(-1490 2975);
DISPLAY 0.978723 (-1490 2975);
FORCEPROP 1 LAST TOLERANCE 5%
J 2
(-1495 3025);
DISPLAY 0.978723 (-1495 3025);
FORCEPROP 1 LAST VALUE 4.7K
J 2
(-1495 3075);
DISPLAY 0.978723 (-1495 3075);
FORCEPROP 1 LAST PART_NUMBER CS24702JB10
J 2
(-1490 2875);
DISPLAY 0.978723 (-1490 2875);
DISPLAY INVISIBLE (-1490 2875);
FORCEPROP 2 LAST CDS_LIB pure_quanta
J 2
(-1450 3000);
DISPLAY INVISIBLE (-1450 3000);
FORCEPROP 2 LAST SEC_TYPE 0402LF
J 2
(-1500 3225);
DISPLAY 0.680851 (-1500 3225);
DISPLAY INVISIBLE (-1500 3225);
FORCEPROP 1 LAST PATH I99
J 2
(-1500 3175);
DISPLAY 0.978723 (-1500 3175);
PAINT WHITE (-1500 3175);
DISPLAY INVISIBLE (-1500 3175);
FORCEADD DNS..1
(-6250 2550);
PAINT RED (-6250 2550);
FORCEPROP 2 LAST BOM_COST VR_SYSTEM 
J 0
(-6425 2725);
DISPLAY 0.680851 (-6425 2725);
DISPLAY INVISIBLE (-6425 2725);
FORCEPROP 2 LAST CDS_LIB mstr_misc
J 0
(-6250 2550);
DISPLAY INVISIBLE (-6250 2550);
FORCEPROP 1 LAST COMMENT_BODY TRUE
J 0
(-6250 2550);
DISPLAY INVISIBLE (-6250 2550);
FORCEADD DNS..1
(-3175 5100);
PAINT RED (-3175 5100);
FORCEPROP 2 LAST CDS_LIB mstr_misc
J 0
(-3175 5100);
DISPLAY INVISIBLE (-3175 5100);
FORCEPROP 2 LAST BOM_COST VR_SYSTEM 
J 0
(-3350 5275);
DISPLAY 0.680851 (-3350 5275);
DISPLAY INVISIBLE (-3350 5275);
FORCEPROP 1 LAST COMMENT_BODY TRUE
J 0
(-3175 5100);
DISPLAY INVISIBLE (-3175 5100);
FORCEADD DNS..1
(-500 5675);
PAINT RED (-500 5675);
FORCEPROP 2 LAST CDS_LIB mstr_misc
J 0
(-500 5675);
DISPLAY INVISIBLE (-500 5675);
FORCEPROP 2 LAST BOM_COST VR_SYSTEM 
J 0
(-675 5850);
DISPLAY 0.680851 (-675 5850);
DISPLAY INVISIBLE (-675 5850);
FORCEPROP 1 LAST COMMENT_BODY TRUE
J 0
(-500 5675);
DISPLAY INVISIBLE (-500 5675);
FORCEADD DNS..1
(-2275 3925);
PAINT RED (-2275 3925);
FORCEPROP 2 LAST CDS_LIB mstr_misc
J 0
(-2275 3925);
DISPLAY INVISIBLE (-2275 3925);
FORCEPROP 2 LAST BOM_COST VR_SYSTEM 
J 0
(-2450 4100);
DISPLAY 0.680851 (-2450 4100);
DISPLAY INVISIBLE (-2450 4100);
FORCEPROP 1 LAST COMMENT_BODY TRUE
J 0
(-2275 3925);
DISPLAY INVISIBLE (-2275 3925);
FORCEADD DNS..1
(-5320 7545);
PAINT RED (-5320 7545);
FORCEPROP 2 LAST BOM_COST VR_SYSTEM 
J 0
(-5500 7725);
DISPLAY 0.680851 (-5500 7725);
DISPLAY INVISIBLE (-5500 7725);
FORCEPROP 2 LAST CDS_LIB mstr_misc
J 0
(-5320 7545);
DISPLAY INVISIBLE (-5320 7545);
FORCEPROP 1 LAST COMMENT_BODY TRUE
J 0
(-5320 7545);
DISPLAY INVISIBLE (-5320 7545);
FORCEADD QUANTA_TITLE_BLOCK_C..1
(1500 1650);
FORCEPROP 0 LAST CDS_CON_LAST_MODIFIED Thu Sep 14 16:12:30 2023
J 0
(-385 1665);
DISPLAY INVISIBLE (-385 1665);
FORCEPROP 2 LAST CUSTOM_TXT_CDS <XR_PAGE_TITLE>
J 0
(-6390 6900);
DISPLAY 0.638298 (-6390 6900);
PAINT PINK (-6390 6900);
DISPLAY INVISIBLE (-6390 6900);
FORCEPROP 2 LAST CUSTOM_TXT_CDS <CON_LAST_MODIFIED>
J 0
(-385 1665);
DISPLAY 0.978723 (-385 1665);
FORCEPROP 2 LAST CUSTOM_TXT_CDS <NAME_1>
J 0
(-1675 1825);
FORCEPROP 2 LAST CUSTOM_TXT_CDS <Q_PROJ>
J 0
(-882 1752);
DISPLAY 1.212766 (-882 1752);
FORCEPROP 2 LAST CUSTOM_TXT_CDS <NAME_2>
J 0
(-1675 1700);
FORCEPROP 2 LAST CUSTOM_TXT_CDS <Q_NUMBER>
J 0
(97 1753);
DISPLAY 1.212766 (97 1753);
FORCEPROP 2 LAST CUSTOM_TXT_CDS <Q_REV>
J 0
(1316 1753);
DISPLAY 1.212766 (1316 1753);
FORCEPROP 2 LAST CUSTOM_TXT_CDS <CON_PAGE_NUM> OF <CON_TOTAL_PAGES>
J 0
(1054 1668);
DISPLAY 0.978723 (1054 1668);
FORCEPROP 1 LAST Q_TITLE P5V & P3V3 SWITCH
J 0
(-7866 1676);
DISPLAY 2.446809 (-7866 1676);
PAINT GREEN (-7866 1676);
FORCEPROP 2 LAST CDS_XR_PAGE_TITLE CR-188 : @T6G_MB_LIB.T6G(SCH_1):PAGE188
J 0
(-6390 6900);
DISPLAY 0.638298 (-6390 6900);
PAINT PINK (-6390 6900);
DISPLAY INVISIBLE (-6390 6900);
FORCEPROP 2 LAST CDS_LIB pure_quanta
J 0
(1500 1650);
DISPLAY INVISIBLE (1500 1650);
FORCEPROP 1 LAST CDS_LMAN_SYM_OUTLINE -9475,6775,100,-125
J 0
(1500 1650);
DISPLAY 0.468085 (1500 1650);
PAINT GREEN (1500 1650);
DISPLAY INVISIBLE (1500 1650);
FORCEPROP 2 LAST PAGE_BORDER TRUE
J 0
(-6390 6900);
DISPLAY 0.638298 (-6390 6900);
PAINT PINK (-6390 6900);
DISPLAY INVISIBLE (-6390 6900);
FORCEPROP 2 LAST BOM_COST VR_SYSTEM 
J 0
(-1675 1850);
DISPLAY 0.680851 (-1675 1850);
DISPLAY INVISIBLE (-1675 1850);
FORCEPROP 1 LAST COMMENT_BODY TRUE
J 0
(1512 1637);
DISPLAY 0.978723 (1512 1637);
PAINT GREEN (1512 1637);
DISPLAY INVISIBLE (1512 1637);
FORCEPROP 1 LAST Q_DEPT CCBU
J 1
(-2263 1699);
DISPLAY 1.957447 (-2263 1699);
PAINT GREEN (-2263 1699);
DISPLAY INVISIBLE (-2263 1699);
FORCEADD DNS..1
(-3225 4575);
PAINT RED (-3225 4575);
FORCEPROP 2 LAST CDS_LIB mstr_misc
J 0
(-3225 4575);
DISPLAY INVISIBLE (-3225 4575);
FORCEPROP 2 LAST BOM_COST VR_SYSTEM 
J 0
(-3400 4750);
DISPLAY 0.680851 (-3400 4750);
DISPLAY INVISIBLE (-3400 4750);
FORCEPROP 1 LAST COMMENT_BODY TRUE
J 0
(-3225 4575);
DISPLAY INVISIBLE (-3225 4575);
WIRE 16 -1 (-1450 3100)(-1450 3225);
WIRE 16 -1 (-1450 2350)(-1450 2225);
WIRE 16 -1 (300 2700)(300 2325);
WIRE 16 -1 (300 3425)(300 3525);
WIRE 16 -1 (-1075 3825)(-1075 3600);
WIRE 16 -1 (-5125 5650)(-5125 5775);
WIRE 16 -1 (-275 3875)(-275 3650);
WIRE 16 -1 (-1075 4675)(-1075 4900);
WIRE 16 -1 (-550 5025)(-550 5250);
WIRE 16 -1 (325 4475)(325 4250);
WIRE 16 -1 (-5500 2825)(-5500 3125);
WIRE 16 -1 (-5350 2275)(-5375 2275);
WIRE 16 -1 (-4750 2275)(-4725 2275);
WIRE 16 -1 (-4600 2950)(-4600 3075);
WIRE 16 -1 (-4350 5125)(-4350 4825);
WIRE 16 -1 (-7575 2025)(-7575 1925);
WIRE 16 -1 (-6750 2425)(-6600 2425);
WIRE 16 -1 (-6600 2425)(-6600 2375);
WIRE 16 -1 (-6200 2650)(-6200 2725);
WIRE 16 -1 (-6175 1950)(-6175 1900);
WIRE 16 -1 (-5675 6625)(-5975 6625);
WIRE 16 -1 (-5975 6625)(-5975 6875);
WIRE 16 -1 (-7225 3625)(-6900 3625);
WIRE 16 -1 (-7225 3625)(-7225 3850);
WIRE 16 -1 (-6650 3625)(-6250 3625);
WIRE 16 -1 (-6250 3625)(-6250 3850);
WIRE 16 -1 (-3950 6225)(-3950 6100);
WIRE 16 -1 (-2350 6425)(-2350 6300);
WIRE 16 -1 (-5775 4575)(-5775 4350);
WIRE 16 -1 (-5125 4800)(-5125 4575);
WIRE 16 -1 (-4275 3425)(-4275 3200);
WIRE 16 -1 (-3375 3775)(-3300 3775);
WIRE 16 -1 (-3300 3775)(-3300 3525);
WIRE 16 -1 (-2875 4350)(-2875 4500);
WIRE 16 -1 (-2800 3625)(-2800 3500);
WIRE 16 -1 (-3200 4475)(-3200 4400);
WIRE 16 -1 (-3175 5175)(-3175 5300);
WIRE 16 -1 (-3375 3975)(-2875 3975);
FORCEPROP 2 LAST SIG_NAME PWRGD_P5V_R
J 0
(-3285 3985);
DISPLAY 0.680851 (-3285 3985);
FORCEPROP 2 LASTPROP $XRERR UNIQUE?
J 0
(-3525 3985);
DISPLAY 0.638298 (-3525 3985);
PAINT MONO (-3525 3985);
DISPLAY INVISIBLE (-3525 3985);
WIRE 16 -1 (-2875 4150)(-2875 3975);
WIRE 16 -1 (-2875 3975)(-2800 3975);
WIRE 16 -1 (-2800 3975)(-2725 3975);
WIRE 16 -1 (-2800 3825)(-2800 3975);
WIRE 16 -1 (-2725 3975)(-2375 3975);
WIRE 16 -1 (-2725 3975)(-2725 2500);
WIRE 16 -1 (-2725 2500)(-2600 2500);
WIRE 16 -1 (-2400 2500)(-1700 2500);
FORCEPROP 2 LAST SIG_NAME PWRGD_P5V_R1
J 0
(-2210 2510);
DISPLAY 0.680851 (-2210 2510);
FORCEPROP 2 LASTPROP $XRERR UNIQUE?
J 0
(-2450 2510);
DISPLAY 0.638298 (-2450 2510);
PAINT MONO (-2450 2510);
DISPLAY INVISIBLE (-2450 2510);
WIRE 16 -1 (-4750 2175)(-4600 2175);
WIRE 16 -1 (-4600 2600)(-4600 2175);
WIRE 16 -1 (-4600 2600)(-4025 2600);
FORCEPROP 2 LAST SIG_NAME PWRGD_P3V3_R1
J 0
(-4410 2610);
DISPLAY 0.489362 (-4410 2610);
FORCEPROP 2 LASTPROP $XRERR UNIQUE?
J 0
(-4650 2610);
DISPLAY 0.638298 (-4650 2610);
PAINT MONO (-4650 2610);
DISPLAY INVISIBLE (-4650 2610);
WIRE 16 -1 (-4600 2750)(-4600 2600);
WIRE 16 -1 (-7500 2325)(-7575 2325);
WIRE 16 -1 (-7575 2575)(-7575 2325);
WIRE 16 -1 (-7575 2225)(-7575 2325);
WIRE 16 -1 (-5325 7475)(-5325 7350);
WIRE 16 -1 (-5325 7350)(-5650 7350);
WIRE 16 -1 (-5650 7475)(-5650 7350);
WIRE 16 -1 (-5975 7350)(-5650 7350);
WIRE 16 -1 (-5975 7475)(-5975 7350);
WIRE 16 -1 (-5975 7350)(-5975 7275);
WIRE 16 -1 (-5975 7675)(-5975 7750);
WIRE 16 -1 (-5975 7750)(-5650 7750);
WIRE 16 -1 (-5325 7750)(-5650 7750);
WIRE 16 -1 (-5650 7675)(-5650 7750);
WIRE 16 -1 (-5325 7750)(-5151 7750);
WIRE 16 -1 (-5325 7675)(-5325 7750);
WIRE 16 -1 (-5151 7824)(-5151 7750);
WIRE 16 -1 (-5151 7750)(-5151 6900);
WIRE 16 -1 (-5151 6900)(-4250 6900);
WIRE 16 -1 (-3050 7325)(-3050 7200);
WIRE 16 -1 (-3050 7200)(-3375 7200);
WIRE 16 -1 (-3375 7325)(-3375 7200);
WIRE 16 -1 (-3375 7200)(-3375 7150);
WIRE 16 -1 (-600 7375)(-600 7525);
WIRE 16 -1 (-1175 7525)(-600 7525);
WIRE 16 -1 (-1175 7375)(-1175 7525);
WIRE 16 -1 (-1750 7525)(-1175 7525);
WIRE 16 -1 (-1750 7375)(-1750 7525);
WIRE 16 -1 (-2350 7525)(-1750 7525);
WIRE 16 -1 (-2350 7600)(-2350 7525);
WIRE 16 -1 (-2350 7525)(-2350 7375);
WIRE 16 -1 (-3050 7600)(-2350 7600);
WIRE 16 -1 (-3050 7525)(-3050 7600);
WIRE 16 -1 (-3375 7600)(-3050 7600);
WIRE 16 -1 (-3375 7525)(-3375 7600);
WIRE 16 -1 (-3375 7600)(-3475 7600);
WIRE 16 -1 (-3475 7000)(-3475 7600);
WIRE 16 -1 (-3475 7600)(-3475 7850);
WIRE 16 -1 (-3475 7000)(-3475 6900);
WIRE 16 -1 (-3750 7000)(-3475 7000);
WIRE 16 -1 (-3475 6900)(-3475 6800);
WIRE 16 -1 (-3475 6900)(-3750 6900);
WIRE 16 -1 (-3475 6800)(-3750 6800);
WIRE 16 -1 (-500 5600)(-500 5475);
WIRE 16 -1 (-500 5475)(-900 5475);
WIRE 16 -1 (-900 5600)(-900 5475);
WIRE 16 -1 (-900 5475)(-1225 5475);
WIRE 16 -1 (-1225 5600)(-1225 5475);
WIRE 16 -1 (-1225 5475)(-1225 5425);
WIRE 16 -1 (-1225 5800)(-1225 5875);
WIRE 16 -1 (-1225 5875)(-900 5875);
WIRE 16 -1 (-500 5875)(-900 5875);
WIRE 16 -1 (-900 5800)(-900 5875);
WIRE 16 -1 (-500 5875)(-326 5875);
WIRE 16 -1 (-500 5800)(-500 5875);
WIRE 16 -1 (-326 6049)(-326 5875);
WIRE 16 -1 (-326 5875)(-326 5250);
WIRE 16 -1 (-326 5250)(-175 5250);
WIRE 16 -1 (725 5600)(725 5475);
WIRE 16 -1 (1100 5475)(725 5475);
WIRE 16 -1 (1100 5600)(1100 5475);
WIRE 16 -1 (1100 5475)(1100 5400);
WIRE 16 -1 (625 5150)(625 5250);
WIRE 16 -1 (625 5150)(325 5150);
WIRE 16 -1 (625 5350)(625 5250);
WIRE 16 -1 (625 5250)(325 5250);
WIRE 16 -1 (625 5350)(625 5875);
WIRE 16 -1 (325 5350)(625 5350);
WIRE 16 -1 (725 5875)(625 5875);
WIRE 16 -1 (625 5875)(625 6050);
WIRE 16 -1 (725 5875)(1100 5875);
WIRE 16 -1 (725 5800)(725 5875);
WIRE 16 -1 (1100 5800)(1100 5875);
WIRE 16 -1 (-4275 4200)(-4275 3875);
WIRE 16 -1 (-4275 3875)(-4125 3875);
WIRE 16 -1 (-4275 3875)(-4275 3625);
WIRE 16 -1 (-3200 4675)(-3200 4775);
WIRE 16 -1 (-3175 4775)(-3200 4775);
WIRE 16 -1 (-3200 4775)(-3775 4775);
FORCEPROP 2 LAST SIG_NAME SW_P3V3_EN
J 0
(-3685 4785);
DISPLAY 0.680851 (-3685 4785);
WIRE 16 -1 (-2575 4775)(-3175 4775);
WIRE 16 -1 (-3175 4975)(-3175 4775);
WIRE 16 -1 (-600 7175)(-600 6975);
WIRE 16 -1 (-600 6975)(-1175 6975);
WIRE 16 -1 (-1175 6975)(-1175 7175);
WIRE 16 -1 (-1175 6975)(-1750 6975);
WIRE 16 -1 (-1750 6975)(-1750 7175);
WIRE 16 -1 (-1750 6975)(-2350 6975);
WIRE 16 -1 (-2350 7175)(-2350 6975);
WIRE 16 -1 (-2350 6825)(-2350 6975);
FORCEPROP 2 LAST SIG_NAME VR_P5V_EN_D
R 1
J 0
(-2360 6885);
DISPLAY 0.638298 (-2360 6885);
PAINT WHITE (-2360 6885);
FORCEPROP 2 LASTPROP $XRERR UNIQUE?
J 0
(-2600 6885);
DISPLAY 0.638298 (-2600 6885);
PAINT MONO (-2600 6885);
DISPLAY INVISIBLE (-2600 6885);
WIRE 16 -1 (-2375 4775)(-1900 4775);
WIRE 16 -1 (-1900 4775)(-1900 3975);
WIRE 16 -1 (-1900 3975)(-1325 3975);
FORCEPROP 2 LAST SIG_NAME SW_P3V3_EN_R
J 0
(-1835 3985);
DISPLAY 0.680851 (-1835 3985);
FORCEPROP 2 LASTPROP $XRERR UNIQUE?
J 0
(-2075 3985);
DISPLAY 0.638298 (-2075 3985);
PAINT MONO (-2075 3985);
DISPLAY INVISIBLE (-2075 3985);
WIRE 16 -1 (-1900 3975)(-2175 3975);
WIRE 16 -1 (-3950 6425)(-3950 6625);
WIRE 16 -1 (-3950 6700)(-3950 6625);
WIRE 16 -1 (-3950 6625)(-4350 6625);
WIRE 16 -1 (-4350 6625)(-4350 6425);
WIRE 16 -1 (-5475 6625)(-4350 6625);
FORCEPROP 2 LAST SIG_NAME VR_P5V_EN_D_R
J 0
(-4910 6625);
DISPLAY 0.617021 (-4910 6625);
PAINT WHITE (-4910 6625);
FORCEPROP 2 LASTPROP $XRERR UNIQUE?
J 0
(-5150 6625);
DISPLAY 0.638298 (-5150 6625);
PAINT MONO (-5150 6625);
DISPLAY INVISIBLE (-5150 6625);
WIRE 16 -1 (-6200 4950)(-5775 4950);
WIRE 16 -1 (-5375 4950)(-5775 4950);
FORCEPROP 2 LAST SIG_NAME VR_P5V_EN
J 0
(-5735 4960);
DISPLAY 0.617021 (-5735 4960);
PAINT WHITE (-5735 4960);
FORCEPROP 2 LASTPROP $XRERR UNIQUE?
J 0
(-5975 4960);
DISPLAY 0.638298 (-5975 4960);
PAINT MONO (-5975 4960);
DISPLAY INVISIBLE (-5975 4960);
WIRE 16 -1 (-5775 4775)(-5775 4950);
WIRE 16 -1 (-5050 5150)(-4850 5150);
WIRE 16 -1 (-5050 5275)(-5050 5150);
WIRE 16 -1 (-5050 5275)(-4600 5275);
WIRE 16 -1 (-5125 5275)(-5050 5275);
FORCEPROP 2 LAST SIG_NAME VR_P5V_EN_N
J 0
(-5035 5285);
DISPLAY 0.617021 (-5035 5285);
PAINT WHITE (-5035 5285);
WIRE 16 -1 (-5125 5450)(-5125 5275);
WIRE 16 -1 (-5125 5200)(-5125 5275);
WIRE 16 -1 (-3325 2600)(-3825 2600);
FORCEPROP 2 LAST SIG_NAME PWRGD_P3V3_R2
J 0
(-3685 2610);
DISPLAY 0.489362 (-3685 2610);
WIRE 16 -1 (-5850 2225)(-5350 2225);
FORCEPROP 2 LAST SIG_NAME PWRGD_P3V3_EN
J 0
(-5835 2250);
DISPLAY 0.489362 (-5835 2250);
FORCEPROP 2 LASTPROP $XRERR UNIQUE?
J 0
(-6075 2250);
DISPLAY 0.638298 (-6075 2250);
PAINT MONO (-6075 2250);
DISPLAY INVISIBLE (-6075 2250);
WIRE 16 -1 (-5350 2175)(-5500 2175);
WIRE 16 -1 (-5500 2625)(-5500 2175);
WIRE 16 -1 (-5500 2175)(-5500 2000);
WIRE 16 -1 (-4725 2000)(-5500 2000);
FORCEPROP 2 LAST SIG_NAME PWRGD_P3V3_EN_N
J 0
(-5235 2025);
DISPLAY 0.489362 (-5235 2025);
FORCEPROP 2 LASTPROP $XRERR UNIQUE?
J 0
(-5475 2025);
DISPLAY 0.638298 (-5475 2025);
PAINT MONO (-5475 2025);
DISPLAY INVISIBLE (-5475 2025);
WIRE 16 -1 (-4725 2225)(-4725 2000);
WIRE 16 -1 (-4750 2225)(-4725 2225);
WIRE 16 -1 (-4350 6225)(-4350 5525);
FORCEPROP 2 LAST SIG_NAME VR_P5V_EN_D_R1
R 1
J 0
(-4360 5610);
DISPLAY 0.617021 (-4360 5610);
PAINT WHITE (-4360 5610);
FORCEPROP 2 LASTPROP $XRERR UNIQUE?
J 0
(-4600 5610);
DISPLAY 0.638298 (-4600 5610);
PAINT MONO (-4600 5610);
DISPLAY INVISIBLE (-4600 5610);
WIRE 16 -1 (-7100 4950)(-6400 4950);
FORCEPROP 2 LAST SIG_NAME FM_P5V_EN
J 0
(-7035 4960);
DISPLAY 0.617021 (-7035 4960);
PAINT WHITE (-7035 4960);
WIRE 16 -1 (50 2850)(-525 2850);
FORCEPROP 2 LAST SIG_NAME PWRGD_P5V_N
J 0
(-385 2860);
DISPLAY 0.680851 (-385 2860);
FORCEPROP 2 LASTPROP $XRERR UNIQUE?
J 0
(-625 2860);
DISPLAY 0.638298 (-625 2860);
PAINT MONO (-625 2860);
DISPLAY INVISIBLE (-625 2860);
WIRE 16 -1 (300 3225)(300 3175);
WIRE 16 -1 (300 3175)(1075 3175);
FORCEPROP 2 LAST SIG_NAME PWRGD_P5V_R2
J 0
(540 3185);
DISPLAY 0.680851 (540 3185);
WIRE 16 -1 (300 3100)(300 3175);
WIRE 16 -1 (-275 4275)(-275 4475);
FORCEPROP 2 LAST SIG_NAME SW_P3V3_EN_ISO
R 1
J 0
(-360 4185);
DISPLAY 0.553191 (-360 4185);
FORCEPROP 2 LASTPROP $XRERR UNIQUE?
J 0
(-600 4185);
DISPLAY 0.638298 (-600 4185);
PAINT MONO (-600 4185);
DISPLAY INVISIBLE (-600 4185);
WIRE 16 -1 (-275 4750)(125 4750);
WIRE 16 -1 (-275 4675)(-275 4750);
WIRE 16 -1 (-275 4750)(-550 4750);
FORCEPROP 2 LAST SIG_NAME SW_P3V3_EN_ISO_R
J 0
(-485 4760);
DISPLAY 0.680851 (-485 4760);
FORCEPROP 2 LASTPROP $XRERR UNIQUE?
J 0
(-725 4760);
DISPLAY 0.638298 (-725 4760);
PAINT MONO (-725 4760);
DISPLAY INVISIBLE (-725 4760);
WIRE 16 -1 (125 4750)(325 4750);
WIRE 16 -1 (125 4750)(125 5050);
WIRE 16 -1 (325 4750)(325 4675);
WIRE 16 -1 (-550 4750)(-550 4825);
WIRE 16 -1 (-1450 2900)(-1450 2850);
WIRE 16 -1 (-1450 2850)(-725 2850);
FORCEPROP 2 LAST SIG_NAME PWRGD_P5V_R_N
J 0
(-1360 2860);
DISPLAY 0.680851 (-1360 2860);
FORCEPROP 2 LASTPROP $XRERR UNIQUE?
J 0
(-1600 2860);
DISPLAY 0.638298 (-1600 2860);
PAINT MONO (-1600 2860);
DISPLAY INVISIBLE (-1600 2860);
WIRE 16 -1 (-1450 2750)(-1450 2850);
WIRE 16 -1 (-2550 6625)(-3075 6625);
FORCEPROP 2 LAST SIG_NAME VR_P5V_EN_N
J 0
(-2985 6635);
DISPLAY 0.617021 (-2985 6635);
PAINT WHITE (-2985 6635);
WIRE 16 -1 (-1075 4250)(-600 4250);
FORCEPROP 2 LAST SIG_NAME SW_P3V3_EN_N
J 0
(-985 4260);
DISPLAY 0.680851 (-985 4260);
FORCEPROP 2 LASTPROP $XRERR UNIQUE?
J 0
(-1225 4260);
DISPLAY 0.638298 (-1225 4260);
PAINT MONO (-1225 4260);
DISPLAY INVISIBLE (-1225 4260);
WIRE 16 -1 (-1075 4475)(-1075 4250);
WIRE 16 -1 (-1075 4225)(-1075 4250);
WIRE 16 -1 (-600 4250)(-600 4025);
WIRE 16 -1 (-600 4025)(-525 4025);
WIRE 16 -1 (-6175 2225)(-6050 2225);
WIRE 16 -1 (-6200 2225)(-6175 2225);
WIRE 16 -1 (-6175 2225)(-6175 2150);
WIRE 16 -1 (-6200 2450)(-6200 2225);
WIRE 16 -1 (-6750 2225)(-6200 2225);
FORCEPROP 2 LAST SIG_NAME PWRGD_P3V3_EN_R
J 0
(-6660 2235);
DISPLAY 0.553191 (-6660 2235);
FORCEPROP 2 LASTPROP $XRERR UNIQUE?
J 0
(-6900 2235);
DISPLAY 0.638298 (-6900 2235);
PAINT MONO (-6900 2235);
DISPLAY INVISIBLE (-6900 2235);
DOT 1 (-5050 5275);
DOT 1 (-5125 5275);
DOT 1 (-4275 3875);
DOT 1 (-6175 2225);
DOT 1 (-6200 2225);
DOT 1 (-7575 2325);
DOT 1 (-5500 2175);
DOT 1 (-4600 2600);
DOT 1 (-4350 6625);
DOT 1 (625 5250);
DOT 1 (625 5350);
DOT 1 (-1075 4250);
DOT 1 (-1225 5475);
DOT 1 (-900 5475);
DOT 1 (-900 5875);
DOT 1 (-500 5875);
DOT 1 (-326 5875);
DOT 1 (625 5875);
DOT 1 (725 5875);
DOT 1 (1100 5475);
DOT 1 (-5775 4950);
DOT 1 (-5975 7350);
DOT 1 (-5650 7350);
DOT 1 (-5650 7750);
DOT 1 (-5325 7750);
DOT 1 (-5151 7750);
DOT 1 (-3950 6625);
DOT 1 (-3475 6900);
DOT 1 (-3375 7200);
DOT 1 (-3475 7600);
DOT 1 (-3375 7600);
DOT 1 (-3050 7600);
DOT 1 (-1750 6975);
DOT 1 (-1175 6975);
DOT 1 (-2350 6975);
DOT 1 (-1750 7525);
DOT 1 (-3475 7000);
DOT 1 (-2800 3975);
DOT 1 (-2875 3975);
DOT 1 (-1450 2850);
DOT 1 (300 3175);
DOT 1 (-3200 4775);
DOT 1 (-275 4750);
DOT 1 (-2725 3975);
DOT 1 (-1900 3975);
DOT 1 (125 4750);
DOT 1 (-2350 7525);
DOT 1 (-1175 7525);
DOT 1 (-3175 4775);
FORCENOTE
PUSH PULL OUTPUT
(-7450 2825) 0;
DISPLAY LEFT (-7450 2825);
DISPLAY 1.021277 (-7450 2825);
FORCENOTE
OD OUTPUT
(-3925 3550) 0;
DISPLAY LEFT (-3925 3550);
DISPLAY 1.021277 (-3925 3550);
QUIT
